(kicad_sch
	(version 20231120)
	(generator "eeschema")
	(generator_version "8.0")
	(paper "A3")
	(title_block
		(title "Jetson Orin Baseboard")
		(date "2025-03-12")
		(rev "1.3.4")
		(company "Antmicro Ltd")
		(comment 1 "www.antmicro.com")
	)
	(junction
		(at 318.77 124.46)
		(diameter 0)
		(color 0 0 0 0)
	)
	(junction
		(at 140.97 125.73)
		(diameter 0)
		(color 0 0 0 0)
	)
	(junction
		(at 257.81 152.4)
		(diameter 0)
		(color 0 0 0 0)
	)
	(junction
		(at 39.37 261.62)
		(diameter 0)
		(color 0 0 0 0)
	)
	(junction
		(at 360.68 40.64)
		(diameter 0)
		(color 0 0 0 0)
	)
	(junction
		(at 198.12 200.66)
		(diameter 0)
		(color 0 0 0 0)
	)
	(junction
		(at 276.86 154.94)
		(diameter 0)
		(color 0 0 0 0)
	)
	(junction
		(at 346.71 219.71)
		(diameter 0)
		(color 0 0 0 0)
	)
	(junction
		(at 325.12 73.66)
		(diameter 0)
		(color 0 0 0 0)
	)
	(junction
		(at 45.72 193.04)
		(diameter 0)
		(color 0 0 0 0)
	)
	(junction
		(at 252.73 170.18)
		(diameter 0)
		(color 0 0 0 0)
	)
	(junction
		(at 76.2 123.19)
		(diameter 0)
		(color 0 0 0 0)
	)
	(junction
		(at 262.89 60.96)
		(diameter 0)
		(color 0 0 0 0)
	)
	(junction
		(at 190.5 66.04)
		(diameter 0)
		(color 0 0 0 0)
	)
	(junction
		(at 90.17 245.11)
		(diameter 0)
		(color 0 0 0 0)
	)
	(junction
		(at 21.59 34.29)
		(diameter 0)
		(color 0 0 0 0)
	)
	(junction
		(at 240.03 207.01)
		(diameter 0)
		(color 0 0 0 0)
	)
	(junction
		(at 168.91 66.04)
		(diameter 0)
		(color 0 0 0 0)
	)
	(junction
		(at 66.04 186.69)
		(diameter 0)
		(color 0 0 0 0)
	)
	(junction
		(at 16.51 34.29)
		(diameter 0)
		(color 0 0 0 0)
	)
	(junction
		(at 40.64 172.72)
		(diameter 0)
		(color 0 0 0 0)
	)
	(junction
		(at 40.64 139.7)
		(diameter 0)
		(color 0 0 0 0)
	)
	(junction
		(at 356.87 222.25)
		(diameter 0)
		(color 0 0 0 0)
	)
	(junction
		(at 201.93 104.14)
		(diameter 0)
		(color 0 0 0 0)
	)
	(junction
		(at 342.9 81.28)
		(diameter 0)
		(color 0 0 0 0)
	)
	(junction
		(at 359.41 219.71)
		(diameter 0)
		(color 0 0 0 0)
	)
	(junction
		(at 341.63 222.25)
		(diameter 0)
		(color 0 0 0 0)
	)
	(junction
		(at 41.91 217.17)
		(diameter 0)
		(color 0 0 0 0)
	)
	(junction
		(at 35.56 193.04)
		(diameter 0)
		(color 0 0 0 0)
	)
	(junction
		(at 140.97 123.19)
		(diameter 0)
		(color 0 0 0 0)
	)
	(junction
		(at 256.54 147.32)
		(diameter 0)
		(color 0 0 0 0)
	)
	(junction
		(at 193.04 260.35)
		(diameter 0)
		(color 0 0 0 0)
	)
	(junction
		(at 346.71 101.6)
		(diameter 0)
		(color 0 0 0 0)
	)
	(junction
		(at 337.82 190.5)
		(diameter 0)
		(color 0 0 0 0)
	)
	(junction
		(at 200.66 66.04)
		(diameter 0)
		(color 0 0 0 0)
	)
	(junction
		(at 187.96 241.3)
		(diameter 0)
		(color 0 0 0 0)
	)
	(junction
		(at 45.72 204.47)
		(diameter 0)
		(color 0 0 0 0)
	)
	(junction
		(at 185.42 212.09)
		(diameter 0)
		(color 0 0 0 0)
	)
	(junction
		(at 344.17 106.68)
		(diameter 0)
		(color 0 0 0 0)
	)
	(junction
		(at 48.26 137.16)
		(diameter 0)
		(color 0 0 0 0)
	)
	(junction
		(at 274.32 162.56)
		(diameter 0)
		(color 0 0 0 0)
	)
	(junction
		(at 173.99 200.66)
		(diameter 0)
		(color 0 0 0 0)
	)
	(junction
		(at 229.87 217.17)
		(diameter 0)
		(color 0 0 0 0)
	)
	(junction
		(at 41.91 64.77)
		(diameter 0)
		(color 0 0 0 0)
	)
	(junction
		(at 50.8 109.22)
		(diameter 0)
		(color 0 0 0 0)
	)
	(junction
		(at 360.68 139.7)
		(diameter 0)
		(color 0 0 0 0)
	)
	(junction
		(at 31.75 251.46)
		(diameter 0)
		(color 0 0 0 0)
	)
	(junction
		(at 21.59 64.77)
		(diameter 0)
		(color 0 0 0 0)
	)
	(junction
		(at 351.79 190.5)
		(diameter 0)
		(color 0 0 0 0)
	)
	(junction
		(at 317.5 190.5)
		(diameter 0)
		(color 0 0 0 0)
	)
	(junction
		(at 323.85 116.84)
		(diameter 0)
		(color 0 0 0 0)
	)
	(junction
		(at 41.91 76.2)
		(diameter 0)
		(color 0 0 0 0)
	)
	(junction
		(at 276.86 144.78)
		(diameter 0)
		(color 0 0 0 0)
	)
	(junction
		(at 198.12 209.55)
		(diameter 0)
		(color 0 0 0 0)
	)
	(junction
		(at 273.05 83.82)
		(diameter 0)
		(color 0 0 0 0)
	)
	(junction
		(at 29.21 172.72)
		(diameter 0)
		(color 0 0 0 0)
	)
	(junction
		(at 45.72 201.93)
		(diameter 0)
		(color 0 0 0 0)
	)
	(junction
		(at 360.68 190.5)
		(diameter 0)
		(color 0 0 0 0)
	)
	(junction
		(at 273.05 34.29)
		(diameter 0)
		(color 0 0 0 0)
	)
	(junction
		(at 252.73 50.8)
		(diameter 0)
		(color 0 0 0 0)
	)
	(junction
		(at 358.14 73.66)
		(diameter 0)
		(color 0 0 0 0)
	)
	(junction
		(at 25.4 193.04)
		(diameter 0)
		(color 0 0 0 0)
	)
	(junction
		(at 254 165.1)
		(diameter 0)
		(color 0 0 0 0)
	)
	(junction
		(at 157.48 66.04)
		(diameter 0)
		(color 0 0 0 0)
	)
	(junction
		(at 256.54 160.02)
		(diameter 0)
		(color 0 0 0 0)
	)
	(junction
		(at 370.84 139.7)
		(diameter 0)
		(color 0 0 0 0)
	)
	(junction
		(at 179.07 66.04)
		(diameter 0)
		(color 0 0 0 0)
	)
	(junction
		(at 345.44 93.98)
		(diameter 0)
		(color 0 0 0 0)
	)
	(junction
		(at 170.18 144.78)
		(diameter 0)
		(color 0 0 0 0)
	)
	(junction
		(at 276.86 165.1)
		(diameter 0)
		(color 0 0 0 0)
	)
	(junction
		(at 262.89 34.29)
		(diameter 0)
		(color 0 0 0 0)
	)
	(junction
		(at 254 142.24)
		(diameter 0)
		(color 0 0 0 0)
	)
	(junction
		(at 359.41 129.54)
		(diameter 0)
		(color 0 0 0 0)
	)
	(junction
		(at 367.03 93.98)
		(diameter 0)
		(color 0 0 0 0)
	)
	(junction
		(at 297.18 129.54)
		(diameter 0)
		(color 0 0 0 0)
	)
	(junction
		(at 274.32 167.64)
		(diameter 0)
		(color 0 0 0 0)
	)
	(junction
		(at 111.76 186.69)
		(diameter 0)
		(color 0 0 0 0)
	)
	(junction
		(at 321.31 114.3)
		(diameter 0)
		(color 0 0 0 0)
	)
	(junction
		(at 204.47 101.6)
		(diameter 0)
		(color 0 0 0 0)
	)
	(junction
		(at 347.98 91.44)
		(diameter 0)
		(color 0 0 0 0)
	)
	(junction
		(at 140.97 128.27)
		(diameter 0)
		(color 0 0 0 0)
	)
	(junction
		(at 386.08 40.64)
		(diameter 0)
		(color 0 0 0 0)
	)
	(junction
		(at 139.7 85.09)
		(diameter 0)
		(color 0 0 0 0)
	)
	(junction
		(at 273.05 53.34)
		(diameter 0)
		(color 0 0 0 0)
	)
	(junction
		(at 185.42 200.66)
		(diameter 0)
		(color 0 0 0 0)
	)
	(junction
		(at 273.05 60.96)
		(diameter 0)
		(color 0 0 0 0)
	)
	(junction
		(at 276.86 160.02)
		(diameter 0)
		(color 0 0 0 0)
	)
	(junction
		(at 193.04 241.3)
		(diameter 0)
		(color 0 0 0 0)
	)
	(junction
		(at 361.95 132.08)
		(diameter 0)
		(color 0 0 0 0)
	)
	(junction
		(at 341.63 109.22)
		(diameter 0)
		(color 0 0 0 0)
	)
	(junction
		(at 274.32 152.4)
		(diameter 0)
		(color 0 0 0 0)
	)
	(junction
		(at 257.81 154.94)
		(diameter 0)
		(color 0 0 0 0)
	)
	(junction
		(at 375.92 40.64)
		(diameter 0)
		(color 0 0 0 0)
	)
	(junction
		(at 358.14 40.64)
		(diameter 0)
		(color 0 0 0 0)
	)
	(junction
		(at 72.39 123.19)
		(diameter 0)
		(color 0 0 0 0)
	)
	(junction
		(at 170.18 147.32)
		(diameter 0)
		(color 0 0 0 0)
	)
	(junction
		(at 316.23 58.42)
		(diameter 0)
		(color 0 0 0 0)
	)
	(junction
		(at 90.17 234.95)
		(diameter 0)
		(color 0 0 0 0)
	)
	(junction
		(at 274.32 157.48)
		(diameter 0)
		(color 0 0 0 0)
	)
	(junction
		(at 274.32 172.72)
		(diameter 0)
		(color 0 0 0 0)
	)
	(junction
		(at 274.32 147.32)
		(diameter 0)
		(color 0 0 0 0)
	)
	(junction
		(at 327.66 190.5)
		(diameter 0)
		(color 0 0 0 0)
	)
	(junction
		(at 316.23 121.92)
		(diameter 0)
		(color 0 0 0 0)
	)
	(junction
		(at 372.11 242.57)
		(diameter 0)
		(color 0 0 0 0)
	)
	(junction
		(at 350.52 78.74)
		(diameter 0)
		(color 0 0 0 0)
	)
	(junction
		(at 349.25 99.06)
		(diameter 0)
		(color 0 0 0 0)
	)
	(junction
		(at 207.01 212.09)
		(diameter 0)
		(color 0 0 0 0)
	)
	(junction
		(at 276.86 139.7)
		(diameter 0)
		(color 0 0 0 0)
	)
	(junction
		(at 39.37 243.84)
		(diameter 0)
		(color 0 0 0 0)
	)
	(junction
		(at 276.86 149.86)
		(diameter 0)
		(color 0 0 0 0)
	)
	(junction
		(at 288.29 53.34)
		(diameter 0)
		(color 0 0 0 0)
	)
	(junction
		(at 93.98 247.65)
		(diameter 0)
		(color 0 0 0 0)
	)
	(junction
		(at 369.57 91.44)
		(diameter 0)
		(color 0 0 0 0)
	)
	(junction
		(at 299.72 132.08)
		(diameter 0)
		(color 0 0 0 0)
	)
	(no_connect
		(at 85.09 209.55)
	)
	(no_connect
		(at 88.9 78.74)
	)
	(no_connect
		(at 88.9 76.2)
	)
	(no_connect
		(at 234.95 267.97)
	)
	(no_connect
		(at 234.95 265.43)
	)
	(no_connect
		(at 373.38 232.41)
	)
	(no_connect
		(at 323.85 86.36)
	)
	(no_connect
		(at 323.85 88.9)
	)
	(no_connect
		(at 113.03 39.37)
	)
	(no_connect
		(at 102.87 39.37)
	)
	(no_connect
		(at 373.38 234.95)
	)
	(no_connect
		(at 292.1 135.89)
	)
	(no_connect
		(at 294.64 135.89)
	)
	(no_connect
		(at 69.85 144.78)
	)
	(wire
		(pts
			(xy 25.4 78.74) (xy 25.4 80.01)
		)
		(stroke
			(width 0)
			(type default)
		)
	)
	(wire
		(pts
			(xy 53.34 46.99) (xy 46.99 46.99)
		)
		(stroke
			(width 0)
			(type default)
		)
	)
	(wire
		(pts
			(xy 274.32 157.48) (xy 274.32 162.56)
		)
		(stroke
			(width 0)
			(type default)
		)
	)
	(wire
		(pts
			(xy 50.8 106.68) (xy 53.34 106.68)
		)
		(stroke
			(width 0)
			(type default)
		)
	)
	(wire
		(pts
			(xy 204.47 165.1) (xy 210.82 165.1)
		)
		(stroke
			(width 0)
			(type default)
		)
	)
	(wire
		(pts
			(xy 204.47 147.32) (xy 210.82 147.32)
		)
		(stroke
			(width 0)
			(type default)
		)
	)
	(wire
		(pts
			(xy 173.99 208.28) (xy 173.99 207.01)
		)
		(stroke
			(width 0)
			(type default)
		)
	)
	(wire
		(pts
			(xy 40.64 177.8) (xy 41.91 177.8)
		)
		(stroke
			(width 0)
			(type default)
		)
	)
	(wire
		(pts
			(xy 236.22 114.3) (xy 321.31 114.3)
		)
		(stroke
			(width 0)
			(type default)
		)
	)
	(wire
		(pts
			(xy 317.5 190.5) (xy 317.5 191.77)
		)
		(stroke
			(width 0)
			(type default)
		)
	)
	(wire
		(pts
			(xy 360.68 139.7) (xy 361.95 139.7)
		)
		(stroke
			(width 0)
			(type default)
		)
	)
	(wire
		(pts
			(xy 267.97 167.64) (xy 274.32 167.64)
		)
		(stroke
			(width 0)
			(type default)
		)
	)
	(wire
		(pts
			(xy 88.9 72.39) (xy 101.6 72.39)
		)
		(stroke
			(width 0)
			(type default)
		)
	)
	(wire
		(pts
			(xy 72.39 247.65) (xy 93.98 247.65)
		)
		(stroke
			(width 0)
			(type default)
		)
	)
	(wire
		(pts
			(xy 193.04 259.08) (xy 193.04 260.35)
		)
		(stroke
			(width 0)
			(type default)
		)
	)
	(wire
		(pts
			(xy 358.14 40.64) (xy 358.14 73.66)
		)
		(stroke
			(width 0)
			(type default)
		)
	)
	(wire
		(pts
			(xy 313.69 190.5) (xy 317.5 190.5)
		)
		(stroke
			(width 0)
			(type default)
		)
	)
	(polyline
		(pts
			(xy 152.4 90.17) (xy 152.4 106.68)
		)
		(stroke
			(width 0)
			(type solid)
		)
	)
	(wire
		(pts
			(xy 236.22 154.94) (xy 257.81 154.94)
		)
		(stroke
			(width 0)
			(type default)
		)
	)
	(wire
		(pts
			(xy 198.12 209.55) (xy 198.12 207.01)
		)
		(stroke
			(width 0)
			(type default)
		)
	)
	(wire
		(pts
			(xy 41.91 130.81) (xy 40.64 130.81)
		)
		(stroke
			(width 0)
			(type default)
		)
	)
	(wire
		(pts
			(xy 105.41 109.22) (xy 88.9 109.22)
		)
		(stroke
			(width 0)
			(type default)
		)
	)
	(wire
		(pts
			(xy 118.11 85.09) (xy 110.49 85.09)
		)
		(stroke
			(width 0)
			(type default)
		)
	)
	(wire
		(pts
			(xy 351.79 203.2) (xy 351.79 204.47)
		)
		(stroke
			(width 0)
			(type default)
		)
	)
	(wire
		(pts
			(xy 372.11 245.11) (xy 372.11 242.57)
		)
		(stroke
			(width 0)
			(type default)
		)
	)
	(wire
		(pts
			(xy 256.54 160.02) (xy 256.54 162.56)
		)
		(stroke
			(width 0)
			(type default)
		)
	)
	(wire
		(pts
			(xy 359.41 138.43) (xy 359.41 139.7)
		)
		(stroke
			(width 0)
			(type default)
		)
	)
	(wire
		(pts
			(xy 316.23 57.15) (xy 316.23 58.42)
		)
		(stroke
			(width 0)
			(type default)
		)
	)
	(wire
		(pts
			(xy 45.72 201.93) (xy 46.99 201.93)
		)
		(stroke
			(width 0)
			(type default)
		)
	)
	(wire
		(pts
			(xy 21.59 55.88) (xy 30.48 55.88)
		)
		(stroke
			(width 0)
			(type default)
		)
	)
	(wire
		(pts
			(xy 41.91 175.26) (xy 40.64 175.26)
		)
		(stroke
			(width 0)
			(type default)
		)
	)
	(wire
		(pts
			(xy 35.56 193.04) (xy 45.72 193.04)
		)
		(stroke
			(width 0)
			(type default)
		)
	)
	(wire
		(pts
			(xy 299.72 242.57) (xy 299.72 243.84)
		)
		(stroke
			(width 0)
			(type default)
		)
	)
	(wire
		(pts
			(xy 88.9 58.42) (xy 107.95 58.42)
		)
		(stroke
			(width 0)
			(type default)
		)
	)
	(wire
		(pts
			(xy 88.9 99.06) (xy 109.22 99.06)
		)
		(stroke
			(width 0)
			(type default)
		)
	)
	(wire
		(pts
			(xy 396.24 53.34) (xy 396.24 54.61)
		)
		(stroke
			(width 0)
			(type default)
		)
	)
	(wire
		(pts
			(xy 200.66 66.04) (xy 200.66 67.31)
		)
		(stroke
			(width 0)
			(type default)
		)
	)
	(wire
		(pts
			(xy 276.86 154.94) (xy 276.86 160.02)
		)
		(stroke
			(width 0)
			(type default)
		)
	)
	(wire
		(pts
			(xy 88.9 60.96) (xy 107.95 60.96)
		)
		(stroke
			(width 0)
			(type default)
		)
	)
	(wire
		(pts
			(xy 227.33 217.17) (xy 229.87 217.17)
		)
		(stroke
			(width 0)
			(type default)
		)
	)
	(wire
		(pts
			(xy 267.97 165.1) (xy 276.86 165.1)
		)
		(stroke
			(width 0)
			(type default)
		)
	)
	(wire
		(pts
			(xy 372.11 86.36) (xy 369.57 86.36)
		)
		(stroke
			(width 0)
			(type default)
		)
	)
	(wire
		(pts
			(xy 29.21 172.72) (xy 40.64 172.72)
		)
		(stroke
			(width 0)
			(type default)
		)
	)
	(wire
		(pts
			(xy 257.81 154.94) (xy 262.89 154.94)
		)
		(stroke
			(width 0)
			(type default)
		)
	)
	(wire
		(pts
			(xy 107.95 130.81) (xy 127 130.81)
		)
		(stroke
			(width 0)
			(type default)
		)
	)
	(wire
		(pts
			(xy 236.22 162.56) (xy 252.73 162.56)
		)
		(stroke
			(width 0)
			(type default)
		)
	)
	(wire
		(pts
			(xy 177.8 121.92) (xy 175.26 124.46)
		)
		(stroke
			(width 0)
			(type default)
		)
	)
	(wire
		(pts
			(xy 107.95 128.27) (xy 127 128.27)
		)
		(stroke
			(width 0)
			(type default)
		)
	)
	(wire
		(pts
			(xy 193.04 172.72) (xy 210.82 172.72)
		)
		(stroke
			(width 0)
			(type default)
		)
	)
	(wire
		(pts
			(xy 262.89 60.96) (xy 262.89 64.77)
		)
		(stroke
			(width 0)
			(type default)
		)
	)
	(wire
		(pts
			(xy 342.9 81.28) (xy 372.11 81.28)
		)
		(stroke
			(width 0)
			(type default)
		)
	)
	(wire
		(pts
			(xy 316.23 50.8) (xy 316.23 52.07)
		)
		(stroke
			(width 0)
			(type default)
		)
	)
	(wire
		(pts
			(xy 114.3 99.06) (xy 121.92 99.06)
		)
		(stroke
			(width 0)
			(type default)
		)
	)
	(wire
		(pts
			(xy 123.19 85.09) (xy 129.54 85.09)
		)
		(stroke
			(width 0)
			(type default)
		)
	)
	(wire
		(pts
			(xy 88.9 44.45) (xy 102.87 44.45)
		)
		(stroke
			(width 0)
			(type default)
		)
	)
	(wire
		(pts
			(xy 351.79 196.85) (xy 351.79 198.12)
		)
		(stroke
			(width 0)
			(type default)
		)
	)
	(wire
		(pts
			(xy 274.32 167.64) (xy 274.32 172.72)
		)
		(stroke
			(width 0)
			(type default)
		)
	)
	(wire
		(pts
			(xy 360.68 207.01) (xy 373.38 207.01)
		)
		(stroke
			(width 0)
			(type default)
		)
	)
	(wire
		(pts
			(xy 283.21 60.96) (xy 283.21 73.66)
		)
		(stroke
			(width 0)
			(type default)
		)
	)
	(wire
		(pts
			(xy 256.54 147.32) (xy 262.89 147.32)
		)
		(stroke
			(width 0)
			(type default)
		)
	)
	(wire
		(pts
			(xy 316.23 58.42) (xy 309.88 58.42)
		)
		(stroke
			(width 0)
			(type default)
		)
	)
	(wire
		(pts
			(xy 370.84 139.7) (xy 372.11 139.7)
		)
		(stroke
			(width 0)
			(type default)
		)
	)
	(wire
		(pts
			(xy 297.18 129.54) (xy 297.18 135.89)
		)
		(stroke
			(width 0)
			(type default)
		)
	)
	(wire
		(pts
			(xy 66.04 186.69) (xy 45.72 186.69)
		)
		(stroke
			(width 0)
			(type default)
		)
	)
	(wire
		(pts
			(xy 285.75 232.41) (xy 300.99 232.41)
		)
		(stroke
			(width 0)
			(type default)
		)
	)
	(wire
		(pts
			(xy 254 142.24) (xy 254 139.7)
		)
		(stroke
			(width 0)
			(type default)
		)
	)
	(wire
		(pts
			(xy 316.23 59.69) (xy 316.23 58.42)
		)
		(stroke
			(width 0)
			(type default)
		)
	)
	(wire
		(pts
			(xy 252.73 33.02) (xy 252.73 35.56)
		)
		(stroke
			(width 0)
			(type default)
		)
	)
	(wire
		(pts
			(xy 168.91 66.04) (xy 179.07 66.04)
		)
		(stroke
			(width 0)
			(type default)
		)
	)
	(wire
		(pts
			(xy 88.9 41.91) (xy 102.87 41.91)
		)
		(stroke
			(width 0)
			(type default)
		)
	)
	(wire
		(pts
			(xy 15.24 193.04) (xy 15.24 194.31)
		)
		(stroke
			(width 0)
			(type default)
		)
	)
	(wire
		(pts
			(xy 21.59 34.29) (xy 52.07 34.29)
		)
		(stroke
			(width 0)
			(type default)
		)
	)
	(wire
		(pts
			(xy 210.82 66.04) (xy 210.82 99.06)
		)
		(stroke
			(width 0)
			(type default)
		)
	)
	(wire
		(pts
			(xy 33.02 40.64) (xy 33.02 39.37)
		)
		(stroke
			(width 0)
			(type default)
		)
	)
	(wire
		(pts
			(xy 38.1 144.78) (xy 50.8 144.78)
		)
		(stroke
			(width 0)
			(type default)
		)
	)
	(wire
		(pts
			(xy 267.97 157.48) (xy 274.32 157.48)
		)
		(stroke
			(width 0)
			(type default)
		)
	)
	(wire
		(pts
			(xy 236.22 109.22) (xy 275.59 109.22)
		)
		(stroke
			(width 0)
			(type default)
		)
	)
	(wire
		(pts
			(xy 177.8 114.3) (xy 175.26 116.84)
		)
		(stroke
			(width 0)
			(type default)
		)
	)
	(wire
		(pts
			(xy 21.59 64.77) (xy 30.48 64.77)
		)
		(stroke
			(width 0)
			(type default)
		)
	)
	(wire
		(pts
			(xy 173.99 172.72) (xy 187.96 172.72)
		)
		(stroke
			(width 0)
			(type default)
		)
	)
	(wire
		(pts
			(xy 262.89 69.85) (xy 262.89 71.12)
		)
		(stroke
			(width 0)
			(type default)
		)
	)
	(wire
		(pts
			(xy 168.91 147.32) (xy 170.18 147.32)
		)
		(stroke
			(width 0)
			(type default)
		)
	)
	(wire
		(pts
			(xy 337.82 190.5) (xy 337.82 191.77)
		)
		(stroke
			(width 0)
			(type default)
		)
	)
	(wire
		(pts
			(xy 69.85 217.17) (xy 111.76 217.17)
		)
		(stroke
			(width 0)
			(type default)
		)
	)
	(wire
		(pts
			(xy 132.08 130.81) (xy 140.97 130.81)
		)
		(stroke
			(width 0)
			(type default)
		)
	)
	(polyline
		(pts
			(xy 12.7 156.21) (xy 146.05 156.21)
		)
		(stroke
			(width 0)
			(type default)
		)
	)
	(wire
		(pts
			(xy 45.72 207.01) (xy 45.72 204.47)
		)
		(stroke
			(width 0)
			(type default)
		)
	)
	(wire
		(pts
			(xy 58.42 175.26) (xy 57.15 175.26)
		)
		(stroke
			(width 0)
			(type default)
		)
	)
	(wire
		(pts
			(xy 289.56 34.29) (xy 273.05 34.29)
		)
		(stroke
			(width 0)
			(type default)
		)
	)
	(wire
		(pts
			(xy 360.68 40.64) (xy 360.68 41.91)
		)
		(stroke
			(width 0)
			(type default)
		)
	)
	(wire
		(pts
			(xy 90.17 234.95) (xy 90.17 236.22)
		)
		(stroke
			(width 0)
			(type default)
		)
	)
	(wire
		(pts
			(xy 323.85 78.74) (xy 350.52 78.74)
		)
		(stroke
			(width 0)
			(type default)
		)
	)
	(wire
		(pts
			(xy 274.32 162.56) (xy 274.32 167.64)
		)
		(stroke
			(width 0)
			(type default)
		)
	)
	(wire
		(pts
			(xy 342.9 93.98) (xy 345.44 93.98)
		)
		(stroke
			(width 0)
			(type default)
		)
	)
	(wire
		(pts
			(xy 132.08 123.19) (xy 140.97 123.19)
		)
		(stroke
			(width 0)
			(type default)
		)
	)
	(wire
		(pts
			(xy 205.74 129.54) (xy 208.28 132.08)
		)
		(stroke
			(width 0)
			(type default)
		)
	)
	(wire
		(pts
			(xy 179.07 66.04) (xy 190.5 66.04)
		)
		(stroke
			(width 0)
			(type default)
		)
	)
	(wire
		(pts
			(xy 69.85 207.01) (xy 73.66 207.01)
		)
		(stroke
			(width 0)
			(type default)
		)
	)
	(wire
		(pts
			(xy 360.68 48.26) (xy 360.68 46.99)
		)
		(stroke
			(width 0)
			(type default)
		)
	)
	(wire
		(pts
			(xy 283.21 137.16) (xy 283.21 134.62)
		)
		(stroke
			(width 0)
			(type default)
		)
	)
	(wire
		(pts
			(xy 314.96 219.71) (xy 330.2 219.71)
		)
		(stroke
			(width 0)
			(type default)
		)
	)
	(wire
		(pts
			(xy 359.41 129.54) (xy 372.11 129.54)
		)
		(stroke
			(width 0)
			(type default)
		)
	)
	(wire
		(pts
			(xy 93.98 241.3) (xy 93.98 247.65)
		)
		(stroke
			(width 0)
			(type default)
		)
	)
	(wire
		(pts
			(xy 88.9 96.52) (xy 109.22 96.52)
		)
		(stroke
			(width 0)
			(type default)
		)
	)
	(wire
		(pts
			(xy 373.38 227.33) (xy 356.87 227.33)
		)
		(stroke
			(width 0)
			(type default)
		)
	)
	(wire
		(pts
			(xy 88.9 81.28) (xy 110.49 81.28)
		)
		(stroke
			(width 0)
			(type default)
		)
	)
	(wire
		(pts
			(xy 203.2 252.73) (xy 201.93 252.73)
		)
		(stroke
			(width 0)
			(type default)
		)
	)
	(wire
		(pts
			(xy 52.07 41.91) (xy 52.07 34.29)
		)
		(stroke
			(width 0)
			(type default)
		)
	)
	(wire
		(pts
			(xy 111.76 186.69) (xy 111.76 187.96)
		)
		(stroke
			(width 0)
			(type default)
		)
	)
	(wire
		(pts
			(xy 130.81 250.19) (xy 130.81 251.46)
		)
		(stroke
			(width 0)
			(type default)
		)
	)
	(wire
		(pts
			(xy 46.99 130.81) (xy 48.26 130.81)
		)
		(stroke
			(width 0)
			(type default)
		)
	)
	(wire
		(pts
			(xy 283.21 134.62) (xy 289.56 134.62)
		)
		(stroke
			(width 0)
			(type default)
		)
	)
	(wire
		(pts
			(xy 267.97 142.24) (xy 274.32 142.24)
		)
		(stroke
			(width 0)
			(type default)
		)
	)
	(wire
		(pts
			(xy 193.04 241.3) (xy 193.04 243.84)
		)
		(stroke
			(width 0)
			(type default)
		)
	)
	(wire
		(pts
			(xy 168.91 72.39) (xy 168.91 73.66)
		)
		(stroke
			(width 0)
			(type default)
		)
	)
	(wire
		(pts
			(xy 318.77 124.46) (xy 318.77 135.89)
		)
		(stroke
			(width 0)
			(type default)
		)
	)
	(wire
		(pts
			(xy 88.9 69.85) (xy 101.6 69.85)
		)
		(stroke
			(width 0)
			(type default)
		)
	)
	(wire
		(pts
			(xy 31.75 261.62) (xy 39.37 261.62)
		)
		(stroke
			(width 0)
			(type default)
		)
	)
	(wire
		(pts
			(xy 323.85 116.84) (xy 323.85 135.89)
		)
		(stroke
			(width 0)
			(type default)
		)
	)
	(wire
		(pts
			(xy 370.84 139.7) (xy 370.84 137.16)
		)
		(stroke
			(width 0)
			(type default)
		)
	)
	(wire
		(pts
			(xy 33.02 39.37) (xy 46.99 39.37)
		)
		(stroke
			(width 0)
			(type default)
		)
	)
	(wire
		(pts
			(xy 168.91 66.04) (xy 168.91 67.31)
		)
		(stroke
			(width 0)
			(type default)
		)
	)
	(wire
		(pts
			(xy 337.82 198.12) (xy 337.82 196.85)
		)
		(stroke
			(width 0)
			(type default)
		)
	)
	(wire
		(pts
			(xy 185.42 241.3) (xy 187.96 241.3)
		)
		(stroke
			(width 0)
			(type default)
		)
	)
	(wire
		(pts
			(xy 177.8 116.84) (xy 184.15 116.84)
		)
		(stroke
			(width 0)
			(type default)
		)
	)
	(polyline
		(pts
			(xy 146.05 181.61) (xy 407.67 181.61)
		)
		(stroke
			(width 0)
			(type default)
		)
	)
	(wire
		(pts
			(xy 88.9 64.77) (xy 101.6 64.77)
		)
		(stroke
			(width 0)
			(type default)
		)
	)
	(polyline
		(pts
			(xy 184.15 106.68) (xy 152.4 106.68)
		)
		(stroke
			(width 0)
			(type solid)
		)
	)
	(wire
		(pts
			(xy 198.12 209.55) (xy 210.82 209.55)
		)
		(stroke
			(width 0)
			(type default)
		)
	)
	(wire
		(pts
			(xy 257.81 53.34) (xy 273.05 53.34)
		)
		(stroke
			(width 0)
			(type default)
		)
	)
	(wire
		(pts
			(xy 207.01 218.44) (xy 207.01 219.71)
		)
		(stroke
			(width 0)
			(type default)
		)
	)
	(wire
		(pts
			(xy 251.46 257.81) (xy 251.46 212.09)
		)
		(stroke
			(width 0)
			(type default)
		)
	)
	(wire
		(pts
			(xy 236.22 116.84) (xy 323.85 116.84)
		)
		(stroke
			(width 0)
			(type default)
		)
	)
	(wire
		(pts
			(xy 207.01 170.18) (xy 210.82 170.18)
		)
		(stroke
			(width 0)
			(type default)
		)
	)
	(wire
		(pts
			(xy 134.62 85.09) (xy 139.7 85.09)
		)
		(stroke
			(width 0)
			(type default)
		)
	)
	(wire
		(pts
			(xy 359.41 219.71) (xy 373.38 219.71)
		)
		(stroke
			(width 0)
			(type default)
		)
	)
	(wire
		(pts
			(xy 62.23 261.62) (xy 62.23 262.89)
		)
		(stroke
			(width 0)
			(type default)
		)
	)
	(wire
		(pts
			(xy 120.65 186.69) (xy 111.76 186.69)
		)
		(stroke
			(width 0)
			(type default)
		)
	)
	(wire
		(pts
			(xy 110.49 85.09) (xy 110.49 83.82)
		)
		(stroke
			(width 0)
			(type default)
		)
	)
	(wire
		(pts
			(xy 173.99 199.39) (xy 173.99 200.66)
		)
		(stroke
			(width 0)
			(type default)
		)
	)
	(wire
		(pts
			(xy 276.86 121.92) (xy 316.23 121.92)
		)
		(stroke
			(width 0)
			(type default)
		)
	)
	(wire
		(pts
			(xy 27.94 36.83) (xy 49.53 36.83)
		)
		(stroke
			(width 0)
			(type default)
		)
	)
	(wire
		(pts
			(xy 189.23 116.84) (xy 210.82 116.84)
		)
		(stroke
			(width 0)
			(type default)
		)
	)
	(wire
		(pts
			(xy 386.08 40.64) (xy 386.08 41.91)
		)
		(stroke
			(width 0)
			(type default)
		)
	)
	(wire
		(pts
			(xy 170.18 147.32) (xy 170.18 149.86)
		)
		(stroke
			(width 0)
			(type default)
		)
	)
	(wire
		(pts
			(xy 78.74 201.93) (xy 83.82 201.93)
		)
		(stroke
			(width 0)
			(type default)
		)
	)
	(wire
		(pts
			(xy 256.54 157.48) (xy 256.54 160.02)
		)
		(stroke
			(width 0)
			(type default)
		)
	)
	(wire
		(pts
			(xy 66.04 172.72) (xy 66.04 186.69)
		)
		(stroke
			(width 0)
			(type default)
		)
	)
	(wire
		(pts
			(xy 276.86 149.86) (xy 276.86 154.94)
		)
		(stroke
			(width 0)
			(type default)
		)
	)
	(wire
		(pts
			(xy 288.29 53.34) (xy 292.1 53.34)
		)
		(stroke
			(width 0)
			(type default)
		)
	)
	(wire
		(pts
			(xy 236.22 172.72) (xy 237.49 172.72)
		)
		(stroke
			(width 0)
			(type default)
		)
	)
	(wire
		(pts
			(xy 299.72 132.08) (xy 361.95 132.08)
		)
		(stroke
			(width 0)
			(type default)
		)
	)
	(wire
		(pts
			(xy 367.03 88.9) (xy 367.03 93.98)
		)
		(stroke
			(width 0)
			(type default)
		)
	)
	(wire
		(pts
			(xy 344.17 106.68) (xy 372.11 106.68)
		)
		(stroke
			(width 0)
			(type default)
		)
	)
	(wire
		(pts
			(xy 12.7 64.77) (xy 21.59 64.77)
		)
		(stroke
			(width 0)
			(type default)
		)
	)
	(wire
		(pts
			(xy 69.85 201.93) (xy 73.66 201.93)
		)
		(stroke
			(width 0)
			(type default)
		)
	)
	(wire
		(pts
			(xy 45.72 186.69) (xy 45.72 193.04)
		)
		(stroke
			(width 0)
			(type default)
		)
	)
	(wire
		(pts
			(xy 40.64 175.26) (xy 40.64 172.72)
		)
		(stroke
			(width 0)
			(type default)
		)
	)
	(wire
		(pts
			(xy 35.56 200.66) (xy 35.56 199.39)
		)
		(stroke
			(width 0)
			(type default)
		)
	)
	(wire
		(pts
			(xy 132.08 125.73) (xy 140.97 125.73)
		)
		(stroke
			(width 0)
			(type default)
		)
	)
	(wire
		(pts
			(xy 273.05 90.17) (xy 273.05 91.44)
		)
		(stroke
			(width 0)
			(type default)
		)
	)
	(wire
		(pts
			(xy 200.66 66.04) (xy 210.82 66.04)
		)
		(stroke
			(width 0)
			(type default)
		)
	)
	(wire
		(pts
			(xy 341.63 109.22) (xy 341.63 135.89)
		)
		(stroke
			(width 0)
			(type default)
		)
	)
	(wire
		(pts
			(xy 140.97 128.27) (xy 140.97 130.81)
		)
		(stroke
			(width 0)
			(type default)
		)
	)
	(wire
		(pts
			(xy 129.54 270.51) (xy 129.54 271.78)
		)
		(stroke
			(width 0)
			(type default)
		)
	)
	(wire
		(pts
			(xy 190.5 72.39) (xy 190.5 73.66)
		)
		(stroke
			(width 0)
			(type default)
		)
	)
	(wire
		(pts
			(xy 31.75 251.46) (xy 33.02 251.46)
		)
		(stroke
			(width 0)
			(type default)
		)
	)
	(wire
		(pts
			(xy 40.64 130.81) (xy 40.64 139.7)
		)
		(stroke
			(width 0)
			(type default)
		)
	)
	(wire
		(pts
			(xy 359.41 139.7) (xy 360.68 139.7)
		)
		(stroke
			(width 0)
			(type default)
		)
	)
	(wire
		(pts
			(xy 21.59 55.88) (xy 21.59 57.15)
		)
		(stroke
			(width 0)
			(type default)
		)
	)
	(wire
		(pts
			(xy 201.93 256.54) (xy 203.2 256.54)
		)
		(stroke
			(width 0)
			(type default)
		)
	)
	(wire
		(pts
			(xy 120.65 187.96) (xy 120.65 186.69)
		)
		(stroke
			(width 0)
			(type default)
		)
	)
	(wire
		(pts
			(xy 236.22 129.54) (xy 297.18 129.54)
		)
		(stroke
			(width 0)
			(type default)
		)
	)
	(wire
		(pts
			(xy 180.34 129.54) (xy 205.74 129.54)
		)
		(stroke
			(width 0)
			(type default)
		)
	)
	(wire
		(pts
			(xy 252.73 172.72) (xy 252.73 170.18)
		)
		(stroke
			(width 0)
			(type default)
		)
	)
	(wire
		(pts
			(xy 27.94 36.83) (xy 27.94 40.64)
		)
		(stroke
			(width 0)
			(type default)
		)
	)
	(wire
		(pts
			(xy 252.73 50.8) (xy 250.19 50.8)
		)
		(stroke
			(width 0)
			(type default)
		)
	)
	(wire
		(pts
			(xy 43.18 259.08) (xy 55.88 259.08)
		)
		(stroke
			(width 0)
			(type default)
		)
	)
	(wire
		(pts
			(xy 193.04 260.35) (xy 193.04 261.62)
		)
		(stroke
			(width 0)
			(type default)
		)
	)
	(wire
		(pts
			(xy 110.49 242.57) (xy 101.6 242.57)
		)
		(stroke
			(width 0)
			(type default)
		)
	)
	(wire
		(pts
			(xy 39.37 241.3) (xy 39.37 243.84)
		)
		(stroke
			(width 0)
			(type default)
		)
	)
	(wire
		(pts
			(xy 66.04 186.69) (xy 111.76 186.69)
		)
		(stroke
			(width 0)
			(type default)
		)
	)
	(wire
		(pts
			(xy 274.32 152.4) (xy 274.32 157.48)
		)
		(stroke
			(width 0)
			(type default)
		)
	)
	(wire
		(pts
			(xy 45.72 222.25) (xy 45.72 227.33)
		)
		(stroke
			(width 0)
			(type default)
		)
	)
	(wire
		(pts
			(xy 207.01 212.09) (xy 203.2 212.09)
		)
		(stroke
			(width 0)
			(type default)
		)
	)
	(wire
		(pts
			(xy 375.92 40.64) (xy 375.92 41.91)
		)
		(stroke
			(width 0)
			(type default)
		)
	)
	(wire
		(pts
			(xy 267.97 160.02) (xy 276.86 160.02)
		)
		(stroke
			(width 0)
			(type default)
		)
	)
	(wire
		(pts
			(xy 289.56 48.26) (xy 292.1 48.26)
		)
		(stroke
			(width 0)
			(type default)
		)
	)
	(polyline
		(pts
			(xy 152.4 93.98) (xy 184.15 93.98)
		)
		(stroke
			(width 0)
			(type solid)
		)
	)
	(wire
		(pts
			(xy 257.81 157.48) (xy 262.89 157.48)
		)
		(stroke
			(width 0)
			(type default)
		)
	)
	(wire
		(pts
			(xy 254 260.35) (xy 254 214.63)
		)
		(stroke
			(width 0)
			(type default)
		)
	)
	(wire
		(pts
			(xy 38.1 137.16) (xy 48.26 137.16)
		)
		(stroke
			(width 0)
			(type default)
		)
	)
	(wire
		(pts
			(xy 226.06 209.55) (xy 229.87 209.55)
		)
		(stroke
			(width 0)
			(type default)
		)
	)
	(wire
		(pts
			(xy 256.54 162.56) (xy 262.89 162.56)
		)
		(stroke
			(width 0)
			(type default)
		)
	)
	(wire
		(pts
			(xy 307.34 137.16) (xy 307.34 134.62)
		)
		(stroke
			(width 0)
			(type default)
		)
	)
	(wire
		(pts
			(xy 16.51 45.72) (xy 16.51 46.99)
		)
		(stroke
			(width 0)
			(type default)
		)
	)
	(wire
		(pts
			(xy 41.91 64.77) (xy 53.34 64.77)
		)
		(stroke
			(width 0)
			(type default)
		)
	)
	(wire
		(pts
			(xy 236.22 160.02) (xy 254 160.02)
		)
		(stroke
			(width 0)
			(type default)
		)
	)
	(wire
		(pts
			(xy 173.99 200.66) (xy 173.99 201.93)
		)
		(stroke
			(width 0)
			(type default)
		)
	)
	(wire
		(pts
			(xy 170.18 142.24) (xy 170.18 144.78)
		)
		(stroke
			(width 0)
			(type default)
		)
	)
	(wire
		(pts
			(xy 45.72 193.04) (xy 45.72 201.93)
		)
		(stroke
			(width 0)
			(type default)
		)
	)
	(wire
		(pts
			(xy 50.8 109.22) (xy 50.8 106.68)
		)
		(stroke
			(width 0)
			(type default)
		)
	)
	(wire
		(pts
			(xy 360.68 190.5) (xy 363.22 190.5)
		)
		(stroke
			(width 0)
			(type default)
		)
	)
	(wire
		(pts
			(xy 276.86 138.43) (xy 276.86 139.7)
		)
		(stroke
			(width 0)
			(type default)
		)
	)
	(wire
		(pts
			(xy 140.97 125.73) (xy 140.97 128.27)
		)
		(stroke
			(width 0)
			(type default)
		)
	)
	(wire
		(pts
			(xy 88.9 83.82) (xy 110.49 83.82)
		)
		(stroke
			(width 0)
			(type default)
		)
	)
	(wire
		(pts
			(xy 170.18 147.32) (xy 182.88 147.32)
		)
		(stroke
			(width 0)
			(type default)
		)
	)
	(polyline
		(pts
			(xy 165.1 90.17) (xy 165.1 106.68)
		)
		(stroke
			(width 0)
			(type solid)
		)
	)
	(wire
		(pts
			(xy 88.9 52.07) (xy 107.95 52.07)
		)
		(stroke
			(width 0)
			(type default)
		)
	)
	(wire
		(pts
			(xy 113.03 41.91) (xy 132.08 41.91)
		)
		(stroke
			(width 0)
			(type default)
		)
	)
	(wire
		(pts
			(xy 113.03 52.07) (xy 120.65 52.07)
		)
		(stroke
			(width 0)
			(type default)
		)
	)
	(wire
		(pts
			(xy 358.14 73.66) (xy 372.11 73.66)
		)
		(stroke
			(width 0)
			(type default)
		)
	)
	(wire
		(pts
			(xy 170.18 154.94) (xy 170.18 156.21)
		)
		(stroke
			(width 0)
			(type default)
		)
	)
	(wire
		(pts
			(xy 105.41 104.14) (xy 88.9 104.14)
		)
		(stroke
			(width 0)
			(type default)
		)
	)
	(wire
		(pts
			(xy 21.59 45.72) (xy 21.59 46.99)
		)
		(stroke
			(width 0)
			(type default)
		)
	)
	(wire
		(pts
			(xy 299.72 132.08) (xy 299.72 135.89)
		)
		(stroke
			(width 0)
			(type default)
		)
	)
	(wire
		(pts
			(xy 157.48 66.04) (xy 157.48 67.31)
		)
		(stroke
			(width 0)
			(type default)
		)
	)
	(polyline
		(pts
			(xy 146.05 181.61) (xy 146.05 12.7)
		)
		(stroke
			(width 0)
			(type default)
		)
	)
	(wire
		(pts
			(xy 93.98 247.65) (xy 110.49 247.65)
		)
		(stroke
			(width 0)
			(type default)
		)
	)
	(wire
		(pts
			(xy 171.45 121.92) (xy 175.26 121.92)
		)
		(stroke
			(width 0)
			(type default)
		)
	)
	(wire
		(pts
			(xy 341.63 222.25) (xy 356.87 222.25)
		)
		(stroke
			(width 0)
			(type default)
		)
	)
	(wire
		(pts
			(xy 396.24 46.99) (xy 396.24 48.26)
		)
		(stroke
			(width 0)
			(type default)
		)
	)
	(wire
		(pts
			(xy 360.68 40.64) (xy 375.92 40.64)
		)
		(stroke
			(width 0)
			(type default)
		)
	)
	(wire
		(pts
			(xy 69.85 219.71) (xy 120.65 219.71)
		)
		(stroke
			(width 0)
			(type default)
		)
	)
	(wire
		(pts
			(xy 177.8 124.46) (xy 184.15 124.46)
		)
		(stroke
			(width 0)
			(type default)
		)
	)
	(wire
		(pts
			(xy 40.64 172.72) (xy 41.91 172.72)
		)
		(stroke
			(width 0)
			(type default)
		)
	)
	(wire
		(pts
			(xy 276.86 106.68) (xy 344.17 106.68)
		)
		(stroke
			(width 0)
			(type default)
		)
	)
	(wire
		(pts
			(xy 123.19 270.51) (xy 129.54 270.51)
		)
		(stroke
			(width 0)
			(type default)
		)
	)
	(wire
		(pts
			(xy 111.76 276.86) (xy 111.76 278.13)
		)
		(stroke
			(width 0)
			(type default)
		)
	)
	(wire
		(pts
			(xy 186.69 121.92) (xy 210.82 121.92)
		)
		(stroke
			(width 0)
			(type default)
		)
	)
	(wire
		(pts
			(xy 48.26 130.81) (xy 48.26 137.16)
		)
		(stroke
			(width 0)
			(type default)
		)
	)
	(wire
		(pts
			(xy 346.71 229.87) (xy 346.71 231.14)
		)
		(stroke
			(width 0)
			(type default)
		)
	)
	(wire
		(pts
			(xy 35.56 64.77) (xy 41.91 64.77)
		)
		(stroke
			(width 0)
			(type default)
		)
	)
	(wire
		(pts
			(xy 359.41 129.54) (xy 359.41 133.35)
		)
		(stroke
			(width 0)
			(type default)
		)
	)
	(wire
		(pts
			(xy 254 167.64) (xy 262.89 167.64)
		)
		(stroke
			(width 0)
			(type default)
		)
	)
	(wire
		(pts
			(xy 309.88 58.42) (xy 309.88 53.34)
		)
		(stroke
			(width 0)
			(type default)
		)
	)
	(wire
		(pts
			(xy 180.34 144.78) (xy 180.34 129.54)
		)
		(stroke
			(width 0)
			(type default)
		)
	)
	(wire
		(pts
			(xy 111.76 193.04) (xy 111.76 199.39)
		)
		(stroke
			(width 0)
			(type default)
		)
	)
	(wire
		(pts
			(xy 171.45 114.3) (xy 175.26 114.3)
		)
		(stroke
			(width 0)
			(type default)
		)
	)
	(wire
		(pts
			(xy 267.97 170.18) (xy 276.86 170.18)
		)
		(stroke
			(width 0)
			(type default)
		)
	)
	(wire
		(pts
			(xy 38.1 139.7) (xy 40.64 139.7)
		)
		(stroke
			(width 0)
			(type default)
		)
	)
	(wire
		(pts
			(xy 187.96 241.3) (xy 193.04 241.3)
		)
		(stroke
			(width 0)
			(type default)
		)
	)
	(wire
		(pts
			(xy 209.55 207.01) (xy 209.55 200.66)
		)
		(stroke
			(width 0)
			(type default)
		)
	)
	(wire
		(pts
			(xy 72.39 134.62) (xy 69.85 134.62)
		)
		(stroke
			(width 0)
			(type default)
		)
	)
	(wire
		(pts
			(xy 344.17 106.68) (xy 344.17 135.89)
		)
		(stroke
			(width 0)
			(type default)
		)
	)
	(wire
		(pts
			(xy 208.28 132.08) (xy 210.82 132.08)
		)
		(stroke
			(width 0)
			(type default)
		)
	)
	(wire
		(pts
			(xy 187.96 104.14) (xy 201.93 104.14)
		)
		(stroke
			(width 0)
			(type default)
		)
	)
	(wire
		(pts
			(xy 204.47 154.94) (xy 210.82 154.94)
		)
		(stroke
			(width 0)
			(type default)
		)
	)
	(wire
		(pts
			(xy 342.9 91.44) (xy 347.98 91.44)
		)
		(stroke
			(width 0)
			(type default)
		)
	)
	(wire
		(pts
			(xy 375.92 46.99) (xy 375.92 48.26)
		)
		(stroke
			(width 0)
			(type default)
		)
	)
	(wire
		(pts
			(xy 187.96 248.92) (xy 187.96 250.19)
		)
		(stroke
			(width 0)
			(type default)
		)
	)
	(wire
		(pts
			(xy 114.3 96.52) (xy 121.92 96.52)
		)
		(stroke
			(width 0)
			(type default)
		)
	)
	(wire
		(pts
			(xy 321.31 114.3) (xy 372.11 114.3)
		)
		(stroke
			(width 0)
			(type default)
		)
	)
	(wire
		(pts
			(xy 107.95 125.73) (xy 127 125.73)
		)
		(stroke
			(width 0)
			(type default)
		)
	)
	(wire
		(pts
			(xy 256.54 149.86) (xy 256.54 147.32)
		)
		(stroke
			(width 0)
			(type default)
		)
	)
	(wire
		(pts
			(xy 41.91 217.17) (xy 46.99 217.17)
		)
		(stroke
			(width 0)
			(type default)
		)
	)
	(wire
		(pts
			(xy 267.97 152.4) (xy 274.32 152.4)
		)
		(stroke
			(width 0)
			(type default)
		)
	)
	(wire
		(pts
			(xy 25.4 67.31) (xy 25.4 68.58)
		)
		(stroke
			(width 0)
			(type default)
		)
	)
	(wire
		(pts
			(xy 283.21 53.34) (xy 288.29 53.34)
		)
		(stroke
			(width 0)
			(type default)
		)
	)
	(wire
		(pts
			(xy 185.42 200.66) (xy 198.12 200.66)
		)
		(stroke
			(width 0)
			(type default)
		)
	)
	(wire
		(pts
			(xy 339.09 134.62) (xy 339.09 135.89)
		)
		(stroke
			(width 0)
			(type default)
		)
	)
	(wire
		(pts
			(xy 396.24 40.64) (xy 396.24 41.91)
		)
		(stroke
			(width 0)
			(type default)
		)
	)
	(wire
		(pts
			(xy 297.18 129.54) (xy 359.41 129.54)
		)
		(stroke
			(width 0)
			(type default)
		)
	)
	(wire
		(pts
			(xy 273.05 83.82) (xy 273.05 85.09)
		)
		(stroke
			(width 0)
			(type default)
		)
	)
	(wire
		(pts
			(xy 114.3 93.98) (xy 121.92 93.98)
		)
		(stroke
			(width 0)
			(type default)
		)
	)
	(wire
		(pts
			(xy 309.88 53.34) (xy 307.34 53.34)
		)
		(stroke
			(width 0)
			(type default)
		)
	)
	(wire
		(pts
			(xy 190.5 66.04) (xy 200.66 66.04)
		)
		(stroke
			(width 0)
			(type default)
		)
	)
	(wire
		(pts
			(xy 63.5 123.19) (xy 72.39 123.19)
		)
		(stroke
			(width 0)
			(type default)
		)
	)
	(wire
		(pts
			(xy 208.28 129.54) (xy 210.82 129.54)
		)
		(stroke
			(width 0)
			(type default)
		)
	)
	(wire
		(pts
			(xy 204.47 162.56) (xy 210.82 162.56)
		)
		(stroke
			(width 0)
			(type default)
		)
	)
	(wire
		(pts
			(xy 227.33 212.09) (xy 227.33 217.17)
		)
		(stroke
			(width 0)
			(type default)
		)
	)
	(wire
		(pts
			(xy 110.49 80.01) (xy 118.11 80.01)
		)
		(stroke
			(width 0)
			(type default)
		)
	)
	(wire
		(pts
			(xy 157.48 72.39) (xy 157.48 73.66)
		)
		(stroke
			(width 0)
			(type default)
		)
	)
	(wire
		(pts
			(xy 267.97 172.72) (xy 274.32 172.72)
		)
		(stroke
			(width 0)
			(type default)
		)
	)
	(wire
		(pts
			(xy 31.75 251.46) (xy 31.75 254)
		)
		(stroke
			(width 0)
			(type default)
		)
	)
	(wire
		(pts
			(xy 236.22 157.48) (xy 256.54 157.48)
		)
		(stroke
			(width 0)
			(type default)
		)
	)
	(wire
		(pts
			(xy 370.84 137.16) (xy 372.11 137.16)
		)
		(stroke
			(width 0)
			(type default)
		)
	)
	(wire
		(pts
			(xy 317.5 196.85) (xy 317.5 198.12)
		)
		(stroke
			(width 0)
			(type default)
		)
	)
	(wire
		(pts
			(xy 260.35 60.96) (xy 262.89 60.96)
		)
		(stroke
			(width 0)
			(type default)
		)
	)
	(wire
		(pts
			(xy 45.72 204.47) (xy 45.72 201.93)
		)
		(stroke
			(width 0)
			(type default)
		)
	)
	(wire
		(pts
			(xy 49.53 44.45) (xy 53.34 44.45)
		)
		(stroke
			(width 0)
			(type default)
		)
	)
	(wire
		(pts
			(xy 72.39 123.19) (xy 72.39 134.62)
		)
		(stroke
			(width 0)
			(type default)
		)
	)
	(wire
		(pts
			(xy 274.32 142.24) (xy 274.32 147.32)
		)
		(stroke
			(width 0)
			(type default)
		)
	)
	(wire
		(pts
			(xy 254 214.63) (xy 373.38 214.63)
		)
		(stroke
			(width 0)
			(type default)
		)
	)
	(wire
		(pts
			(xy 262.89 34.29) (xy 262.89 35.56)
		)
		(stroke
			(width 0)
			(type default)
		)
	)
	(wire
		(pts
			(xy 72.39 245.11) (xy 90.17 245.11)
		)
		(stroke
			(width 0)
			(type default)
		)
	)
	(wire
		(pts
			(xy 345.44 93.98) (xy 367.03 93.98)
		)
		(stroke
			(width 0)
			(type default)
		)
	)
	(wire
		(pts
			(xy 276.86 144.78) (xy 276.86 149.86)
		)
		(stroke
			(width 0)
			(type default)
		)
	)
	(wire
		(pts
			(xy 234.95 257.81) (xy 251.46 257.81)
		)
		(stroke
			(width 0)
			(type default)
		)
	)
	(wire
		(pts
			(xy 349.25 99.06) (xy 349.25 135.89)
		)
		(stroke
			(width 0)
			(type default)
		)
	)
	(wire
		(pts
			(xy 38.1 147.32) (xy 50.8 147.32)
		)
		(stroke
			(width 0)
			(type default)
		)
	)
	(wire
		(pts
			(xy 335.28 219.71) (xy 346.71 219.71)
		)
		(stroke
			(width 0)
			(type default)
		)
	)
	(wire
		(pts
			(xy 76.2 123.19) (xy 77.47 123.19)
		)
		(stroke
			(width 0)
			(type default)
		)
	)
	(wire
		(pts
			(xy 262.89 60.96) (xy 273.05 60.96)
		)
		(stroke
			(width 0)
			(type default)
		)
	)
	(wire
		(pts
			(xy 25.4 200.66) (xy 25.4 199.39)
		)
		(stroke
			(width 0)
			(type default)
		)
	)
	(wire
		(pts
			(xy 123.19 80.01) (xy 129.54 80.01)
		)
		(stroke
			(width 0)
			(type default)
		)
	)
	(wire
		(pts
			(xy 78.74 207.01) (xy 83.82 207.01)
		)
		(stroke
			(width 0)
			(type default)
		)
	)
	(wire
		(pts
			(xy 257.81 152.4) (xy 257.81 149.86)
		)
		(stroke
			(width 0)
			(type default)
		)
	)
	(wire
		(pts
			(xy 182.88 132.08) (xy 205.74 132.08)
		)
		(stroke
			(width 0)
			(type default)
		)
	)
	(wire
		(pts
			(xy 88.9 55.88) (xy 107.95 55.88)
		)
		(stroke
			(width 0)
			(type default)
		)
	)
	(wire
		(pts
			(xy 236.22 124.46) (xy 275.59 124.46)
		)
		(stroke
			(width 0)
			(type default)
		)
	)
	(wire
		(pts
			(xy 359.41 224.79) (xy 359.41 219.71)
		)
		(stroke
			(width 0)
			(type default)
		)
	)
	(wire
		(pts
			(xy 34.29 217.17) (xy 41.91 217.17)
		)
		(stroke
			(width 0)
			(type default)
		)
	)
	(wire
		(pts
			(xy 40.64 139.7) (xy 50.8 139.7)
		)
		(stroke
			(width 0)
			(type default)
		)
	)
	(wire
		(pts
			(xy 16.51 34.29) (xy 21.59 34.29)
		)
		(stroke
			(width 0)
			(type default)
		)
	)
	(wire
		(pts
			(xy 349.25 99.06) (xy 372.11 99.06)
		)
		(stroke
			(width 0)
			(type default)
		)
	)
	(wire
		(pts
			(xy 177.8 121.92) (xy 181.61 121.92)
		)
		(stroke
			(width 0)
			(type default)
		)
	)
	(wire
		(pts
			(xy 31.75 259.08) (xy 31.75 261.62)
		)
		(stroke
			(width 0)
			(type default)
		)
	)
	(wire
		(pts
			(xy 111.76 217.17) (xy 111.76 204.47)
		)
		(stroke
			(width 0)
			(type default)
		)
	)
	(wire
		(pts
			(xy 327.66 190.5) (xy 337.82 190.5)
		)
		(stroke
			(width 0)
			(type default)
		)
	)
	(wire
		(pts
			(xy 198.12 200.66) (xy 209.55 200.66)
		)
		(stroke
			(width 0)
			(type default)
		)
	)
	(wire
		(pts
			(xy 201.93 241.3) (xy 193.04 241.3)
		)
		(stroke
			(width 0)
			(type default)
		)
	)
	(wire
		(pts
			(xy 139.7 80.01) (xy 139.7 85.09)
		)
		(stroke
			(width 0)
			(type default)
		)
	)
	(wire
		(pts
			(xy 88.9 86.36) (xy 106.68 86.36)
		)
		(stroke
			(width 0)
			(type default)
		)
	)
	(wire
		(pts
			(xy 226.06 212.09) (xy 227.33 212.09)
		)
		(stroke
			(width 0)
			(type default)
		)
	)
	(wire
		(pts
			(xy 252.73 170.18) (xy 252.73 162.56)
		)
		(stroke
			(width 0)
			(type default)
		)
	)
	(wire
		(pts
			(xy 187.96 101.6) (xy 204.47 101.6)
		)
		(stroke
			(width 0)
			(type default)
		)
	)
	(wire
		(pts
			(xy 234.95 252.73) (xy 240.03 252.73)
		)
		(stroke
			(width 0)
			(type default)
		)
	)
	(wire
		(pts
			(xy 69.85 222.25) (xy 90.17 222.25)
		)
		(stroke
			(width 0)
			(type default)
		)
	)
	(wire
		(pts
			(xy 361.95 132.08) (xy 372.11 132.08)
		)
		(stroke
			(width 0)
			(type default)
		)
	)
	(wire
		(pts
			(xy 30.48 251.46) (xy 31.75 251.46)
		)
		(stroke
			(width 0)
			(type default)
		)
	)
	(wire
		(pts
			(xy 93.98 234.95) (xy 93.98 236.22)
		)
		(stroke
			(width 0)
			(type default)
		)
	)
	(wire
		(pts
			(xy 254 165.1) (xy 254 167.64)
		)
		(stroke
			(width 0)
			(type default)
		)
	)
	(wire
		(pts
			(xy 361.95 139.7) (xy 361.95 138.43)
		)
		(stroke
			(width 0)
			(type default)
		)
	)
	(wire
		(pts
			(xy 229.87 217.17) (xy 229.87 219.71)
		)
		(stroke
			(width 0)
			(type default)
		)
	)
	(wire
		(pts
			(xy 346.71 219.71) (xy 359.41 219.71)
		)
		(stroke
			(width 0)
			(type default)
		)
	)
	(wire
		(pts
			(xy 267.97 144.78) (xy 276.86 144.78)
		)
		(stroke
			(width 0)
			(type default)
		)
	)
	(wire
		(pts
			(xy 15.24 199.39) (xy 15.24 200.66)
		)
		(stroke
			(width 0)
			(type default)
		)
	)
	(wire
		(pts
			(xy 257.81 152.4) (xy 262.89 152.4)
		)
		(stroke
			(width 0)
			(type default)
		)
	)
	(wire
		(pts
			(xy 337.82 190.5) (xy 351.79 190.5)
		)
		(stroke
			(width 0)
			(type default)
		)
	)
	(wire
		(pts
			(xy 48.26 137.16) (xy 50.8 137.16)
		)
		(stroke
			(width 0)
			(type default)
		)
	)
	(wire
		(pts
			(xy 285.75 88.9) (xy 292.1 88.9)
		)
		(stroke
			(width 0)
			(type default)
		)
	)
	(wire
		(pts
			(xy 171.45 116.84) (xy 175.26 116.84)
		)
		(stroke
			(width 0)
			(type default)
		)
	)
	(wire
		(pts
			(xy 273.05 53.34) (xy 273.05 40.64)
		)
		(stroke
			(width 0)
			(type default)
		)
	)
	(wire
		(pts
			(xy 285.75 237.49) (xy 300.99 237.49)
		)
		(stroke
			(width 0)
			(type default)
		)
	)
	(wire
		(pts
			(xy 251.46 212.09) (xy 373.38 212.09)
		)
		(stroke
			(width 0)
			(type default)
		)
	)
	(wire
		(pts
			(xy 27.94 45.72) (xy 27.94 46.99)
		)
		(stroke
			(width 0)
			(type default)
		)
	)
	(wire
		(pts
			(xy 29.21 172.72) (xy 29.21 173.99)
		)
		(stroke
			(width 0)
			(type default)
		)
	)
	(wire
		(pts
			(xy 29.21 180.34) (xy 29.21 179.07)
		)
		(stroke
			(width 0)
			(type default)
		)
	)
	(wire
		(pts
			(xy 356.87 227.33) (xy 356.87 222.25)
		)
		(stroke
			(width 0)
			(type default)
		)
	)
	(wire
		(pts
			(xy 41.91 217.17) (xy 41.91 220.98)
		)
		(stroke
			(width 0)
			(type default)
		)
	)
	(wire
		(pts
			(xy 39.37 243.84) (xy 62.23 243.84)
		)
		(stroke
			(width 0)
			(type default)
		)
	)
	(wire
		(pts
			(xy 130.81 247.65) (xy 156.21 247.65)
		)
		(stroke
			(width 0)
			(type default)
		)
	)
	(wire
		(pts
			(xy 351.79 190.5) (xy 351.79 191.77)
		)
		(stroke
			(width 0)
			(type default)
		)
	)
	(polyline
		(pts
			(xy 152.4 96.52) (xy 184.15 96.52)
		)
		(stroke
			(width 0)
			(type solid)
		)
	)
	(wire
		(pts
			(xy 359.41 224.79) (xy 373.38 224.79)
		)
		(stroke
			(width 0)
			(type default)
		)
	)
	(wire
		(pts
			(xy 40.64 123.19) (xy 58.42 123.19)
		)
		(stroke
			(width 0)
			(type default)
		)
	)
	(wire
		(pts
			(xy 350.52 64.77) (xy 350.52 78.74)
		)
		(stroke
			(width 0)
			(type default)
		)
	)
	(wire
		(pts
			(xy 346.71 219.71) (xy 346.71 224.79)
		)
		(stroke
			(width 0)
			(type default)
		)
	)
	(wire
		(pts
			(xy 16.51 34.29) (xy 16.51 40.64)
		)
		(stroke
			(width 0)
			(type default)
		)
	)
	(wire
		(pts
			(xy 170.18 144.78) (xy 180.34 144.78)
		)
		(stroke
			(width 0)
			(type default)
		)
	)
	(wire
		(pts
			(xy 372.11 88.9) (xy 367.03 88.9)
		)
		(stroke
			(width 0)
			(type default)
		)
	)
	(wire
		(pts
			(xy 21.59 76.2) (xy 30.48 76.2)
		)
		(stroke
			(width 0)
			(type default)
		)
	)
	(wire
		(pts
			(xy 273.05 60.96) (xy 273.05 64.77)
		)
		(stroke
			(width 0)
			(type default)
		)
	)
	(wire
		(pts
			(xy 226.06 207.01) (xy 240.03 207.01)
		)
		(stroke
			(width 0)
			(type default)
		)
	)
	(wire
		(pts
			(xy 129.54 276.86) (xy 129.54 278.13)
		)
		(stroke
			(width 0)
			(type default)
		)
	)
	(wire
		(pts
			(xy 386.08 40.64) (xy 396.24 40.64)
		)
		(stroke
			(width 0)
			(type default)
		)
	)
	(wire
		(pts
			(xy 38.1 134.62) (xy 50.8 134.62)
		)
		(stroke
			(width 0)
			(type default)
		)
	)
	(wire
		(pts
			(xy 35.56 193.04) (xy 35.56 194.31)
		)
		(stroke
			(width 0)
			(type default)
		)
	)
	(wire
		(pts
			(xy 323.85 81.28) (xy 342.9 81.28)
		)
		(stroke
			(width 0)
			(type default)
		)
	)
	(wire
		(pts
			(xy 39.37 234.95) (xy 39.37 236.22)
		)
		(stroke
			(width 0)
			(type default)
		)
	)
	(wire
		(pts
			(xy 240.03 207.01) (xy 240.03 252.73)
		)
		(stroke
			(width 0)
			(type default)
		)
	)
	(wire
		(pts
			(xy 25.4 78.74) (xy 30.48 78.74)
		)
		(stroke
			(width 0)
			(type default)
		)
	)
	(wire
		(pts
			(xy 204.47 95.25) (xy 204.47 101.6)
		)
		(stroke
			(width 0)
			(type default)
		)
	)
	(wire
		(pts
			(xy 229.87 209.55) (xy 229.87 210.82)
		)
		(stroke
			(width 0)
			(type default)
		)
	)
	(polyline
		(pts
			(xy 184.15 90.17) (xy 184.15 106.68)
		)
		(stroke
			(width 0)
			(type solid)
		)
	)
	(wire
		(pts
			(xy 39.37 254) (xy 39.37 261.62)
		)
		(stroke
			(width 0)
			(type default)
		)
	)
	(wire
		(pts
			(xy 78.74 209.55) (xy 85.09 209.55)
		)
		(stroke
			(width 0)
			(type default)
		)
	)
	(wire
		(pts
			(xy 195.58 209.55) (xy 198.12 209.55)
		)
		(stroke
			(width 0)
			(type default)
		)
	)
	(wire
		(pts
			(xy 335.28 222.25) (xy 341.63 222.25)
		)
		(stroke
			(width 0)
			(type default)
		)
	)
	(wire
		(pts
			(xy 278.13 53.34) (xy 273.05 53.34)
		)
		(stroke
			(width 0)
			(type default)
		)
	)
	(wire
		(pts
			(xy 236.22 149.86) (xy 256.54 149.86)
		)
		(stroke
			(width 0)
			(type default)
		)
	)
	(wire
		(pts
			(xy 372.11 242.57) (xy 372.11 240.03)
		)
		(stroke
			(width 0)
			(type default)
		)
	)
	(wire
		(pts
			(xy 240.03 207.01) (xy 313.69 207.01)
		)
		(stroke
			(width 0)
			(type default)
		)
	)
	(wire
		(pts
			(xy 110.49 81.28) (xy 110.49 80.01)
		)
		(stroke
			(width 0)
			(type default)
		)
	)
	(wire
		(pts
			(xy 41.91 64.77) (xy 41.91 67.31)
		)
		(stroke
			(width 0)
			(type default)
		)
	)
	(wire
		(pts
			(xy 342.9 64.77) (xy 342.9 81.28)
		)
		(stroke
			(width 0)
			(type default)
		)
	)
	(wire
		(pts
			(xy 360.68 190.5) (xy 360.68 207.01)
		)
		(stroke
			(width 0)
			(type default)
		)
	)
	(polyline
		(pts
			(xy 161.29 181.61) (xy 161.29 284.48)
		)
		(stroke
			(width 0)
			(type default)
		)
	)
	(wire
		(pts
			(xy 26.67 172.72) (xy 29.21 172.72)
		)
		(stroke
			(width 0)
			(type default)
		)
	)
	(polyline
		(pts
			(xy 158.75 90.17) (xy 158.75 106.68)
		)
		(stroke
			(width 0)
			(type solid)
		)
	)
	(wire
		(pts
			(xy 53.34 41.91) (xy 52.07 41.91)
		)
		(stroke
			(width 0)
			(type default)
		)
	)
	(wire
		(pts
			(xy 46.99 210.82) (xy 26.67 210.82)
		)
		(stroke
			(width 0)
			(type default)
		)
	)
	(wire
		(pts
			(xy 185.42 218.44) (xy 170.18 218.44)
		)
		(stroke
			(width 0)
			(type default)
		)
	)
	(wire
		(pts
			(xy 189.23 124.46) (xy 210.82 124.46)
		)
		(stroke
			(width 0)
			(type default)
		)
	)
	(wire
		(pts
			(xy 285.75 240.03) (xy 300.99 240.03)
		)
		(stroke
			(width 0)
			(type default)
		)
	)
	(wire
		(pts
			(xy 195.58 267.97) (xy 203.2 267.97)
		)
		(stroke
			(width 0)
			(type default)
		)
	)
	(wire
		(pts
			(xy 276.86 165.1) (xy 276.86 170.18)
		)
		(stroke
			(width 0)
			(type default)
		)
	)
	(wire
		(pts
			(xy 350.52 78.74) (xy 372.11 78.74)
		)
		(stroke
			(width 0)
			(type default)
		)
	)
	(wire
		(pts
			(xy 21.59 34.29) (xy 21.59 40.64)
		)
		(stroke
			(width 0)
			(type default)
		)
	)
	(wire
		(pts
			(xy 361.95 132.08) (xy 361.95 133.35)
		)
		(stroke
			(width 0)
			(type default)
		)
	)
	(wire
		(pts
			(xy 340.36 64.77) (xy 340.36 66.04)
		)
		(stroke
			(width 0)
			(type default)
		)
	)
	(wire
		(pts
			(xy 96.52 250.19) (xy 110.49 250.19)
		)
		(stroke
			(width 0)
			(type default)
		)
	)
	(wire
		(pts
			(xy 254 165.1) (xy 262.89 165.1)
		)
		(stroke
			(width 0)
			(type default)
		)
	)
	(wire
		(pts
			(xy 267.97 149.86) (xy 276.86 149.86)
		)
		(stroke
			(width 0)
			(type default)
		)
	)
	(wire
		(pts
			(xy 204.47 82.55) (xy 204.47 90.17)
		)
		(stroke
			(width 0)
			(type default)
		)
	)
	(wire
		(pts
			(xy 204.47 149.86) (xy 210.82 149.86)
		)
		(stroke
			(width 0)
			(type default)
		)
	)
	(wire
		(pts
			(xy 186.69 114.3) (xy 210.82 114.3)
		)
		(stroke
			(width 0)
			(type default)
		)
	)
	(wire
		(pts
			(xy 113.03 44.45) (xy 132.08 44.45)
		)
		(stroke
			(width 0)
			(type default)
		)
	)
	(wire
		(pts
			(xy 76.2 130.81) (xy 76.2 132.08)
		)
		(stroke
			(width 0)
			(type default)
		)
	)
	(wire
		(pts
			(xy 267.97 139.7) (xy 276.86 139.7)
		)
		(stroke
			(width 0)
			(type default)
		)
	)
	(wire
		(pts
			(xy 289.56 34.29) (xy 289.56 48.26)
		)
		(stroke
			(width 0)
			(type default)
		)
	)
	(wire
		(pts
			(xy 120.65 193.04) (xy 120.65 199.39)
		)
		(stroke
			(width 0)
			(type default)
		)
	)
	(wire
		(pts
			(xy 257.81 157.48) (xy 257.81 154.94)
		)
		(stroke
			(width 0)
			(type default)
		)
	)
	(wire
		(pts
			(xy 256.54 147.32) (xy 256.54 144.78)
		)
		(stroke
			(width 0)
			(type default)
		)
	)
	(wire
		(pts
			(xy 187.96 106.68) (xy 210.82 106.68)
		)
		(stroke
			(width 0)
			(type default)
		)
	)
	(wire
		(pts
			(xy 262.89 33.02) (xy 262.89 34.29)
		)
		(stroke
			(width 0)
			(type default)
		)
	)
	(wire
		(pts
			(xy 283.21 83.82) (xy 283.21 77.47)
		)
		(stroke
			(width 0)
			(type default)
		)
	)
	(wire
		(pts
			(xy 341.63 222.25) (xy 341.63 224.79)
		)
		(stroke
			(width 0)
			(type default)
		)
	)
	(wire
		(pts
			(xy 76.2 123.19) (xy 76.2 125.73)
		)
		(stroke
			(width 0)
			(type default)
		)
	)
	(wire
		(pts
			(xy 369.57 86.36) (xy 369.57 91.44)
		)
		(stroke
			(width 0)
			(type default)
		)
	)
	(wire
		(pts
			(xy 185.42 200.66) (xy 185.42 201.93)
		)
		(stroke
			(width 0)
			(type default)
		)
	)
	(wire
		(pts
			(xy 375.92 40.64) (xy 386.08 40.64)
		)
		(stroke
			(width 0)
			(type default)
		)
	)
	(wire
		(pts
			(xy 199.39 85.09) (xy 201.93 85.09)
		)
		(stroke
			(width 0)
			(type default)
		)
	)
	(wire
		(pts
			(xy 273.05 69.85) (xy 273.05 71.12)
		)
		(stroke
			(width 0)
			(type default)
		)
	)
	(wire
		(pts
			(xy 41.91 226.06) (xy 41.91 227.33)
		)
		(stroke
			(width 0)
			(type default)
		)
	)
	(wire
		(pts
			(xy 207.01 212.09) (xy 210.82 212.09)
		)
		(stroke
			(width 0)
			(type default)
		)
	)
	(wire
		(pts
			(xy 370.84 142.24) (xy 370.84 139.7)
		)
		(stroke
			(width 0)
			(type default)
		)
	)
	(wire
		(pts
			(xy 187.96 241.3) (xy 187.96 243.84)
		)
		(stroke
			(width 0)
			(type default)
		)
	)
	(wire
		(pts
			(xy 325.12 73.66) (xy 358.14 73.66)
		)
		(stroke
			(width 0)
			(type default)
		)
	)
	(wire
		(pts
			(xy 46.99 213.36) (xy 26.67 213.36)
		)
		(stroke
			(width 0)
			(type default)
		)
	)
	(wire
		(pts
			(xy 367.03 93.98) (xy 372.11 93.98)
		)
		(stroke
			(width 0)
			(type default)
		)
	)
	(wire
		(pts
			(xy 317.5 190.5) (xy 327.66 190.5)
		)
		(stroke
			(width 0)
			(type default)
		)
	)
	(wire
		(pts
			(xy 254 142.24) (xy 262.89 142.24)
		)
		(stroke
			(width 0)
			(type default)
		)
	)
	(wire
		(pts
			(xy 50.8 109.22) (xy 50.8 111.76)
		)
		(stroke
			(width 0)
			(type default)
		)
	)
	(wire
		(pts
			(xy 182.88 132.08) (xy 182.88 147.32)
		)
		(stroke
			(width 0)
			(type default)
		)
	)
	(wire
		(pts
			(xy 175.26 114.3) (xy 177.8 116.84)
		)
		(stroke
			(width 0)
			(type default)
		)
	)
	(wire
		(pts
			(xy 193.04 266.7) (xy 193.04 267.97)
		)
		(stroke
			(width 0)
			(type default)
		)
	)
	(wire
		(pts
			(xy 46.99 207.01) (xy 45.72 207.01)
		)
		(stroke
			(width 0)
			(type default)
		)
	)
	(wire
		(pts
			(xy 204.47 139.7) (xy 210.82 139.7)
		)
		(stroke
			(width 0)
			(type default)
		)
	)
	(polyline
		(pts
			(xy 152.4 102.87) (xy 184.15 102.87)
		)
		(stroke
			(width 0)
			(type solid)
		)
	)
	(wire
		(pts
			(xy 177.8 114.3) (xy 181.61 114.3)
		)
		(stroke
			(width 0)
			(type default)
		)
	)
	(wire
		(pts
			(xy 307.34 48.26) (xy 325.12 48.26)
		)
		(stroke
			(width 0)
			(type default)
		)
	)
	(wire
		(pts
			(xy 234.95 260.35) (xy 254 260.35)
		)
		(stroke
			(width 0)
			(type default)
		)
	)
	(wire
		(pts
			(xy 276.86 160.02) (xy 276.86 165.1)
		)
		(stroke
			(width 0)
			(type default)
		)
	)
	(wire
		(pts
			(xy 185.42 212.09) (xy 185.42 207.01)
		)
		(stroke
			(width 0)
			(type default)
		)
	)
	(wire
		(pts
			(xy 120.65 219.71) (xy 120.65 204.47)
		)
		(stroke
			(width 0)
			(type default)
		)
	)
	(wire
		(pts
			(xy 273.05 34.29) (xy 273.05 35.56)
		)
		(stroke
			(width 0)
			(type default)
		)
	)
	(wire
		(pts
			(xy 267.97 154.94) (xy 276.86 154.94)
		)
		(stroke
			(width 0)
			(type default)
		)
	)
	(wire
		(pts
			(xy 90.17 241.3) (xy 90.17 245.11)
		)
		(stroke
			(width 0)
			(type default)
		)
	)
	(wire
		(pts
			(xy 41.91 78.74) (xy 41.91 76.2)
		)
		(stroke
			(width 0)
			(type default)
		)
	)
	(wire
		(pts
			(xy 46.99 46.99) (xy 46.99 39.37)
		)
		(stroke
			(width 0)
			(type default)
		)
	)
	(wire
		(pts
			(xy 41.91 76.2) (xy 53.34 76.2)
		)
		(stroke
			(width 0)
			(type default)
		)
	)
	(wire
		(pts
			(xy 140.97 119.38) (xy 140.97 123.19)
		)
		(stroke
			(width 0)
			(type default)
		)
	)
	(wire
		(pts
			(xy 327.66 190.5) (xy 327.66 191.77)
		)
		(stroke
			(width 0)
			(type default)
		)
	)
	(wire
		(pts
			(xy 316.23 121.92) (xy 316.23 135.89)
		)
		(stroke
			(width 0)
			(type default)
		)
	)
	(wire
		(pts
			(xy 118.11 270.51) (xy 111.76 270.51)
		)
		(stroke
			(width 0)
			(type default)
		)
	)
	(wire
		(pts
			(xy 90.17 245.11) (xy 110.49 245.11)
		)
		(stroke
			(width 0)
			(type default)
		)
	)
	(wire
		(pts
			(xy 171.45 124.46) (xy 175.26 124.46)
		)
		(stroke
			(width 0)
			(type default)
		)
	)
	(wire
		(pts
			(xy 200.66 72.39) (xy 200.66 73.66)
		)
		(stroke
			(width 0)
			(type default)
		)
	)
	(wire
		(pts
			(xy 386.08 46.99) (xy 386.08 48.26)
		)
		(stroke
			(width 0)
			(type default)
		)
	)
	(wire
		(pts
			(xy 372.11 240.03) (xy 373.38 240.03)
		)
		(stroke
			(width 0)
			(type default)
		)
	)
	(wire
		(pts
			(xy 173.99 200.66) (xy 185.42 200.66)
		)
		(stroke
			(width 0)
			(type default)
		)
	)
	(wire
		(pts
			(xy 252.73 40.64) (xy 252.73 50.8)
		)
		(stroke
			(width 0)
			(type default)
		)
	)
	(wire
		(pts
			(xy 280.67 109.22) (xy 341.63 109.22)
		)
		(stroke
			(width 0)
			(type default)
		)
	)
	(wire
		(pts
			(xy 88.9 49.53) (xy 132.08 49.53)
		)
		(stroke
			(width 0)
			(type default)
		)
	)
	(wire
		(pts
			(xy 69.85 214.63) (xy 90.17 214.63)
		)
		(stroke
			(width 0)
			(type default)
		)
	)
	(wire
		(pts
			(xy 236.22 101.6) (xy 346.71 101.6)
		)
		(stroke
			(width 0)
			(type default)
		)
	)
	(wire
		(pts
			(xy 25.4 193.04) (xy 25.4 194.31)
		)
		(stroke
			(width 0)
			(type default)
		)
	)
	(wire
		(pts
			(xy 316.23 121.92) (xy 372.11 121.92)
		)
		(stroke
			(width 0)
			(type default)
		)
	)
	(wire
		(pts
			(xy 262.89 34.29) (xy 273.05 34.29)
		)
		(stroke
			(width 0)
			(type default)
		)
	)
	(wire
		(pts
			(xy 274.32 147.32) (xy 274.32 152.4)
		)
		(stroke
			(width 0)
			(type default)
		)
	)
	(wire
		(pts
			(xy 185.42 212.09) (xy 198.12 212.09)
		)
		(stroke
			(width 0)
			(type default)
		)
	)
	(wire
		(pts
			(xy 39.37 234.95) (xy 30.48 234.95)
		)
		(stroke
			(width 0)
			(type default)
		)
	)
	(wire
		(pts
			(xy 134.62 80.01) (xy 139.7 80.01)
		)
		(stroke
			(width 0)
			(type default)
		)
	)
	(wire
		(pts
			(xy 273.05 60.96) (xy 283.21 60.96)
		)
		(stroke
			(width 0)
			(type default)
		)
	)
	(wire
		(pts
			(xy 57.15 172.72) (xy 66.04 172.72)
		)
		(stroke
			(width 0)
			(type default)
		)
	)
	(wire
		(pts
			(xy 90.17 234.95) (xy 93.98 234.95)
		)
		(stroke
			(width 0)
			(type default)
		)
	)
	(wire
		(pts
			(xy 15.24 193.04) (xy 25.4 193.04)
		)
		(stroke
			(width 0)
			(type default)
		)
	)
	(wire
		(pts
			(xy 254 160.02) (xy 254 165.1)
		)
		(stroke
			(width 0)
			(type default)
		)
	)
	(wire
		(pts
			(xy 283.21 73.66) (xy 292.1 73.66)
		)
		(stroke
			(width 0)
			(type default)
		)
	)
	(wire
		(pts
			(xy 347.98 91.44) (xy 369.57 91.44)
		)
		(stroke
			(width 0)
			(type default)
		)
	)
	(wire
		(pts
			(xy 33.02 45.72) (xy 33.02 46.99)
		)
		(stroke
			(width 0)
			(type default)
		)
	)
	(wire
		(pts
			(xy 323.85 116.84) (xy 372.11 116.84)
		)
		(stroke
			(width 0)
			(type default)
		)
	)
	(wire
		(pts
			(xy 111.76 270.51) (xy 111.76 271.78)
		)
		(stroke
			(width 0)
			(type default)
		)
	)
	(wire
		(pts
			(xy 313.69 207.01) (xy 313.69 190.5)
		)
		(stroke
			(width 0)
			(type default)
		)
	)
	(wire
		(pts
			(xy 207.01 213.36) (xy 207.01 212.09)
		)
		(stroke
			(width 0)
			(type default)
		)
	)
	(wire
		(pts
			(xy 236.22 147.32) (xy 254 147.32)
		)
		(stroke
			(width 0)
			(type default)
		)
	)
	(wire
		(pts
			(xy 267.97 147.32) (xy 274.32 147.32)
		)
		(stroke
			(width 0)
			(type default)
		)
	)
	(wire
		(pts
			(xy 346.71 101.6) (xy 372.11 101.6)
		)
		(stroke
			(width 0)
			(type default)
		)
	)
	(wire
		(pts
			(xy 236.22 121.92) (xy 271.78 121.92)
		)
		(stroke
			(width 0)
			(type default)
		)
	)
	(wire
		(pts
			(xy 347.98 64.77) (xy 347.98 91.44)
		)
		(stroke
			(width 0)
			(type default)
		)
	)
	(wire
		(pts
			(xy 341.63 109.22) (xy 372.11 109.22)
		)
		(stroke
			(width 0)
			(type default)
		)
	)
	(wire
		(pts
			(xy 288.29 53.34) (xy 288.29 54.61)
		)
		(stroke
			(width 0)
			(type default)
		)
	)
	(wire
		(pts
			(xy 49.53 36.83) (xy 49.53 44.45)
		)
		(stroke
			(width 0)
			(type default)
		)
	)
	(wire
		(pts
			(xy 46.99 222.25) (xy 45.72 222.25)
		)
		(stroke
			(width 0)
			(type default)
		)
	)
	(wire
		(pts
			(xy 204.47 157.48) (xy 210.82 157.48)
		)
		(stroke
			(width 0)
			(type default)
		)
	)
	(wire
		(pts
			(xy 372.11 242.57) (xy 373.38 242.57)
		)
		(stroke
			(width 0)
			(type default)
		)
	)
	(wire
		(pts
			(xy 69.85 147.32) (xy 71.12 147.32)
		)
		(stroke
			(width 0)
			(type default)
		)
	)
	(wire
		(pts
			(xy 83.82 232.41) (xy 90.17 232.41)
		)
		(stroke
			(width 0)
			(type default)
		)
	)
	(wire
		(pts
			(xy 107.95 123.19) (xy 127 123.19)
		)
		(stroke
			(width 0)
			(type default)
		)
	)
	(wire
		(pts
			(xy 262.89 40.64) (xy 262.89 41.91)
		)
		(stroke
			(width 0)
			(type default)
		)
	)
	(wire
		(pts
			(xy 199.39 82.55) (xy 204.47 82.55)
		)
		(stroke
			(width 0)
			(type default)
		)
	)
	(wire
		(pts
			(xy 179.07 72.39) (xy 179.07 73.66)
		)
		(stroke
			(width 0)
			(type default)
		)
	)
	(wire
		(pts
			(xy 38.1 142.24) (xy 50.8 142.24)
		)
		(stroke
			(width 0)
			(type default)
		)
	)
	(wire
		(pts
			(xy 35.56 67.31) (xy 41.91 67.31)
		)
		(stroke
			(width 0)
			(type default)
		)
	)
	(wire
		(pts
			(xy 193.04 260.35) (xy 201.93 260.35)
		)
		(stroke
			(width 0)
			(type default)
		)
	)
	(wire
		(pts
			(xy 237.49 172.72) (xy 237.49 173.99)
		)
		(stroke
			(width 0)
			(type default)
		)
	)
	(wire
		(pts
			(xy 236.22 99.06) (xy 349.25 99.06)
		)
		(stroke
			(width 0)
			(type default)
		)
	)
	(wire
		(pts
			(xy 88.9 88.9) (xy 106.68 88.9)
		)
		(stroke
			(width 0)
			(type default)
		)
	)
	(wire
		(pts
			(xy 204.47 101.6) (xy 210.82 101.6)
		)
		(stroke
			(width 0)
			(type default)
		)
	)
	(wire
		(pts
			(xy 201.93 85.09) (xy 201.93 90.17)
		)
		(stroke
			(width 0)
			(type default)
		)
	)
	(wire
		(pts
			(xy 185.42 212.09) (xy 185.42 218.44)
		)
		(stroke
			(width 0)
			(type default)
		)
	)
	(wire
		(pts
			(xy 204.47 142.24) (xy 210.82 142.24)
		)
		(stroke
			(width 0)
			(type default)
		)
	)
	(wire
		(pts
			(xy 229.87 217.17) (xy 229.87 215.9)
		)
		(stroke
			(width 0)
			(type default)
		)
	)
	(wire
		(pts
			(xy 208.28 129.54) (xy 205.74 132.08)
		)
		(stroke
			(width 0)
			(type default)
		)
	)
	(wire
		(pts
			(xy 288.29 59.69) (xy 288.29 60.96)
		)
		(stroke
			(width 0)
			(type default)
		)
	)
	(wire
		(pts
			(xy 332.74 134.62) (xy 339.09 134.62)
		)
		(stroke
			(width 0)
			(type default)
		)
	)
	(wire
		(pts
			(xy 283.21 77.47) (xy 292.1 77.47)
		)
		(stroke
			(width 0)
			(type default)
		)
	)
	(wire
		(pts
			(xy 25.4 67.31) (xy 30.48 67.31)
		)
		(stroke
			(width 0)
			(type default)
		)
	)
	(wire
		(pts
			(xy 132.08 128.27) (xy 140.97 128.27)
		)
		(stroke
			(width 0)
			(type default)
		)
	)
	(wire
		(pts
			(xy 252.73 172.72) (xy 262.89 172.72)
		)
		(stroke
			(width 0)
			(type default)
		)
	)
	(wire
		(pts
			(xy 58.42 179.07) (xy 58.42 175.26)
		)
		(stroke
			(width 0)
			(type default)
		)
	)
	(wire
		(pts
			(xy 198.12 201.93) (xy 198.12 200.66)
		)
		(stroke
			(width 0)
			(type default)
		)
	)
	(wire
		(pts
			(xy 71.12 148.59) (xy 71.12 147.32)
		)
		(stroke
			(width 0)
			(type default)
		)
	)
	(wire
		(pts
			(xy 280.67 124.46) (xy 318.77 124.46)
		)
		(stroke
			(width 0)
			(type default)
		)
	)
	(wire
		(pts
			(xy 351.79 190.5) (xy 360.68 190.5)
		)
		(stroke
			(width 0)
			(type default)
		)
	)
	(wire
		(pts
			(xy 88.9 46.99) (xy 102.87 46.99)
		)
		(stroke
			(width 0)
			(type default)
		)
	)
	(wire
		(pts
			(xy 325.12 48.26) (xy 325.12 73.66)
		)
		(stroke
			(width 0)
			(type default)
		)
	)
	(wire
		(pts
			(xy 25.4 193.04) (xy 35.56 193.04)
		)
		(stroke
			(width 0)
			(type default)
		)
	)
	(wire
		(pts
			(xy 318.77 124.46) (xy 372.11 124.46)
		)
		(stroke
			(width 0)
			(type default)
		)
	)
	(wire
		(pts
			(xy 35.56 76.2) (xy 41.91 76.2)
		)
		(stroke
			(width 0)
			(type default)
		)
	)
	(wire
		(pts
			(xy 307.34 50.8) (xy 316.23 50.8)
		)
		(stroke
			(width 0)
			(type default)
		)
	)
	(wire
		(pts
			(xy 35.56 78.74) (xy 41.91 78.74)
		)
		(stroke
			(width 0)
			(type default)
		)
	)
	(wire
		(pts
			(xy 201.93 260.35) (xy 201.93 256.54)
		)
		(stroke
			(width 0)
			(type default)
		)
	)
	(wire
		(pts
			(xy 236.22 152.4) (xy 257.81 152.4)
		)
		(stroke
			(width 0)
			(type default)
		)
	)
	(wire
		(pts
			(xy 274.32 172.72) (xy 274.32 173.99)
		)
		(stroke
			(width 0)
			(type default)
		)
	)
	(wire
		(pts
			(xy 313.69 134.62) (xy 313.69 135.89)
		)
		(stroke
			(width 0)
			(type default)
		)
	)
	(wire
		(pts
			(xy 327.66 196.85) (xy 327.66 198.12)
		)
		(stroke
			(width 0)
			(type default)
		)
	)
	(wire
		(pts
			(xy 130.81 242.57) (xy 139.7 242.57)
		)
		(stroke
			(width 0)
			(type default)
		)
	)
	(wire
		(pts
			(xy 201.93 104.14) (xy 210.82 104.14)
		)
		(stroke
			(width 0)
			(type default)
		)
	)
	(wire
		(pts
			(xy 40.64 177.8) (xy 40.64 179.07)
		)
		(stroke
			(width 0)
			(type default)
		)
	)
	(wire
		(pts
			(xy 236.22 106.68) (xy 271.78 106.68)
		)
		(stroke
			(width 0)
			(type default)
		)
	)
	(wire
		(pts
			(xy 252.73 50.8) (xy 292.1 50.8)
		)
		(stroke
			(width 0)
			(type default)
		)
	)
	(wire
		(pts
			(xy 78.74 204.47) (xy 83.82 204.47)
		)
		(stroke
			(width 0)
			(type default)
		)
	)
	(wire
		(pts
			(xy 157.48 64.77) (xy 157.48 66.04)
		)
		(stroke
			(width 0)
			(type default)
		)
	)
	(wire
		(pts
			(xy 105.41 106.68) (xy 88.9 106.68)
		)
		(stroke
			(width 0)
			(type default)
		)
	)
	(wire
		(pts
			(xy 139.7 85.09) (xy 139.7 86.36)
		)
		(stroke
			(width 0)
			(type default)
		)
	)
	(wire
		(pts
			(xy 113.03 46.99) (xy 132.08 46.99)
		)
		(stroke
			(width 0)
			(type default)
		)
	)
	(wire
		(pts
			(xy 300.99 242.57) (xy 299.72 242.57)
		)
		(stroke
			(width 0)
			(type default)
		)
	)
	(wire
		(pts
			(xy 369.57 91.44) (xy 372.11 91.44)
		)
		(stroke
			(width 0)
			(type default)
		)
	)
	(wire
		(pts
			(xy 170.18 135.89) (xy 170.18 137.16)
		)
		(stroke
			(width 0)
			(type default)
		)
	)
	(wire
		(pts
			(xy 358.14 40.64) (xy 360.68 40.64)
		)
		(stroke
			(width 0)
			(type default)
		)
	)
	(wire
		(pts
			(xy 201.93 95.25) (xy 201.93 104.14)
		)
		(stroke
			(width 0)
			(type default)
		)
	)
	(wire
		(pts
			(xy 314.96 222.25) (xy 330.2 222.25)
		)
		(stroke
			(width 0)
			(type default)
		)
	)
	(wire
		(pts
			(xy 273.05 82.55) (xy 273.05 83.82)
		)
		(stroke
			(width 0)
			(type default)
		)
	)
	(wire
		(pts
			(xy 210.82 207.01) (xy 209.55 207.01)
		)
		(stroke
			(width 0)
			(type default)
		)
	)
	(wire
		(pts
			(xy 157.48 66.04) (xy 168.91 66.04)
		)
		(stroke
			(width 0)
			(type default)
		)
	)
	(wire
		(pts
			(xy 321.31 114.3) (xy 321.31 135.89)
		)
		(stroke
			(width 0)
			(type default)
		)
	)
	(wire
		(pts
			(xy 355.6 40.64) (xy 358.14 40.64)
		)
		(stroke
			(width 0)
			(type default)
		)
	)
	(wire
		(pts
			(xy 35.56 55.88) (xy 53.34 55.88)
		)
		(stroke
			(width 0)
			(type default)
		)
	)
	(wire
		(pts
			(xy 323.85 73.66) (xy 325.12 73.66)
		)
		(stroke
			(width 0)
			(type default)
		)
	)
	(wire
		(pts
			(xy 256.54 144.78) (xy 262.89 144.78)
		)
		(stroke
			(width 0)
			(type default)
		)
	)
	(wire
		(pts
			(xy 201.93 252.73) (xy 201.93 241.3)
		)
		(stroke
			(width 0)
			(type default)
		)
	)
	(wire
		(pts
			(xy 307.34 134.62) (xy 313.69 134.62)
		)
		(stroke
			(width 0)
			(type default)
		)
	)
	(wire
		(pts
			(xy 90.17 232.41) (xy 90.17 234.95)
		)
		(stroke
			(width 0)
			(type default)
		)
	)
	(wire
		(pts
			(xy 88.9 67.31) (xy 101.6 67.31)
		)
		(stroke
			(width 0)
			(type default)
		)
	)
	(wire
		(pts
			(xy 285.75 234.95) (xy 300.99 234.95)
		)
		(stroke
			(width 0)
			(type default)
		)
	)
	(wire
		(pts
			(xy 69.85 209.55) (xy 73.66 209.55)
		)
		(stroke
			(width 0)
			(type default)
		)
	)
	(wire
		(pts
			(xy 252.73 170.18) (xy 262.89 170.18)
		)
		(stroke
			(width 0)
			(type default)
		)
	)
	(wire
		(pts
			(xy 256.54 160.02) (xy 262.89 160.02)
		)
		(stroke
			(width 0)
			(type default)
		)
	)
	(wire
		(pts
			(xy 39.37 261.62) (xy 39.37 262.89)
		)
		(stroke
			(width 0)
			(type default)
		)
	)
	(wire
		(pts
			(xy 53.34 109.22) (xy 50.8 109.22)
		)
		(stroke
			(width 0)
			(type default)
		)
	)
	(wire
		(pts
			(xy 341.63 229.87) (xy 341.63 231.14)
		)
		(stroke
			(width 0)
			(type default)
		)
	)
	(wire
		(pts
			(xy 16.51 217.17) (xy 29.21 217.17)
		)
		(stroke
			(width 0)
			(type default)
		)
	)
	(wire
		(pts
			(xy 276.86 139.7) (xy 276.86 144.78)
		)
		(stroke
			(width 0)
			(type default)
		)
	)
	(wire
		(pts
			(xy 236.22 132.08) (xy 299.72 132.08)
		)
		(stroke
			(width 0)
			(type default)
		)
	)
	(polyline
		(pts
			(xy 152.4 100.33) (xy 184.15 100.33)
		)
		(stroke
			(width 0)
			(type solid)
		)
	)
	(wire
		(pts
			(xy 130.81 245.11) (xy 156.21 245.11)
		)
		(stroke
			(width 0)
			(type default)
		)
	)
	(wire
		(pts
			(xy 356.87 222.25) (xy 373.38 222.25)
		)
		(stroke
			(width 0)
			(type default)
		)
	)
	(wire
		(pts
			(xy 254 147.32) (xy 254 142.24)
		)
		(stroke
			(width 0)
			(type default)
		)
	)
	(wire
		(pts
			(xy 88.9 93.98) (xy 109.22 93.98)
		)
		(stroke
			(width 0)
			(type default)
		)
	)
	(wire
		(pts
			(xy 257.81 149.86) (xy 262.89 149.86)
		)
		(stroke
			(width 0)
			(type default)
		)
	)
	(wire
		(pts
			(xy 289.56 134.62) (xy 289.56 135.89)
		)
		(stroke
			(width 0)
			(type default)
		)
	)
	(wire
		(pts
			(xy 267.97 162.56) (xy 274.32 162.56)
		)
		(stroke
			(width 0)
			(type default)
		)
	)
	(wire
		(pts
			(xy 273.05 83.82) (xy 283.21 83.82)
		)
		(stroke
			(width 0)
			(type default)
		)
	)
	(wire
		(pts
			(xy 190.5 66.04) (xy 190.5 67.31)
		)
		(stroke
			(width 0)
			(type default)
		)
	)
	(wire
		(pts
			(xy 72.39 123.19) (xy 76.2 123.19)
		)
		(stroke
			(width 0)
			(type default)
		)
	)
	(wire
		(pts
			(xy 140.97 123.19) (xy 140.97 125.73)
		)
		(stroke
			(width 0)
			(type default)
		)
	)
	(wire
		(pts
			(xy 168.91 144.78) (xy 170.18 144.78)
		)
		(stroke
			(width 0)
			(type default)
		)
	)
	(wire
		(pts
			(xy 175.26 121.92) (xy 177.8 124.46)
		)
		(stroke
			(width 0)
			(type default)
		)
	)
	(wire
		(pts
			(xy 69.85 204.47) (xy 73.66 204.47)
		)
		(stroke
			(width 0)
			(type default)
		)
	)
	(wire
		(pts
			(xy 193.04 248.92) (xy 193.04 250.19)
		)
		(stroke
			(width 0)
			(type default)
		)
	)
	(wire
		(pts
			(xy 62.23 243.84) (xy 62.23 251.46)
		)
		(stroke
			(width 0)
			(type default)
		)
	)
	(wire
		(pts
			(xy 254 139.7) (xy 262.89 139.7)
		)
		(stroke
			(width 0)
			(type default)
		)
	)
	(wire
		(pts
			(xy 345.44 64.77) (xy 345.44 93.98)
		)
		(stroke
			(width 0)
			(type default)
		)
	)
	(wire
		(pts
			(xy 21.59 64.77) (xy 21.59 76.2)
		)
		(stroke
			(width 0)
			(type default)
		)
	)
	(wire
		(pts
			(xy 45.72 204.47) (xy 46.99 204.47)
		)
		(stroke
			(width 0)
			(type default)
		)
	)
	(wire
		(pts
			(xy 16.51 31.75) (xy 16.51 34.29)
		)
		(stroke
			(width 0)
			(type default)
		)
	)
	(polyline
		(pts
			(xy 152.4 90.17) (xy 184.15 90.17)
		)
		(stroke
			(width 0)
			(type solid)
		)
	)
	(wire
		(pts
			(xy 360.68 139.7) (xy 360.68 140.97)
		)
		(stroke
			(width 0)
			(type default)
		)
	)
	(wire
		(pts
			(xy 332.74 137.16) (xy 332.74 134.62)
		)
		(stroke
			(width 0)
			(type default)
		)
	)
	(wire
		(pts
			(xy 346.71 101.6) (xy 346.71 135.89)
		)
		(stroke
			(width 0)
			(type default)
		)
	)
	(wire
		(pts
			(xy 179.07 66.04) (xy 179.07 67.31)
		)
		(stroke
			(width 0)
			(type default)
		)
	)
	(text "USB-UART Bridge"
		(exclude_from_sim no)
		(at 109.22 163.83 0)
		(effects
			(font
				(size 4 4)
				(thickness 0.8)
				(bold yes)
			)
			(justify right bottom)
		)
	)
	(text "H"
		(exclude_from_sim no)
		(at 160.02 105.41 0)
		(effects
			(font
				(size 1.27 1.27)
			)
			(justify left bottom)
		)
	)
	(text "POWER DOWN"
		(exclude_from_sim no)
		(at 165.1 95.885 0)
		(effects
			(font
				(size 1.27 1.27)
			)
			(justify left bottom)
		)
	)
	(text "USB PD Controller\n"
		(exclude_from_sim no)
		(at 106.045 20.32 0)
		(effects
			(font
				(size 4 4)
				(thickness 0.8)
				(bold yes)
			)
			(justify right bottom)
		)
	)
	(text "H"
		(exclude_from_sim no)
		(at 153.67 105.41 0)
		(effects
			(font
				(size 1.27 1.27)
			)
			(justify left bottom)
		)
	)
	(text "USB-PD Source/Sink"
		(exclude_from_sim no)
		(at 293.37 25.4 0)
		(effects
			(font
				(size 2.5 2.5)
				(bold yes)
			)
			(justify right bottom)
		)
	)
	(text "TX\n"
		(exclude_from_sim no)
		(at 120.65 196.215 0)
		(effects
			(font
				(size 1.27 1.27)
			)
			(justify left bottom)
		)
	)
	(text "USB-C 0 Display Port alt mode"
		(exclude_from_sim no)
		(at 224.79 20.32 0)
		(effects
			(font
				(size 4 4)
				(thickness 0.8)
				(bold yes)
			)
			(justify left bottom)
		)
	)
	(text "4 LANE DP"
		(exclude_from_sim no)
		(at 165.1 102.235 0)
		(effects
			(font
				(size 1.27 1.27)
			)
			(justify left bottom)
		)
	)
	(text "L"
		(exclude_from_sim no)
		(at 160.02 95.885 0)
		(effects
			(font
				(size 1.27 1.27)
			)
			(justify left bottom)
		)
	)
	(text "USB-PD Source/Sink"
		(exclude_from_sim no)
		(at 283.21 195.58 0)
		(effects
			(font
				(size 2.5 2.5)
				(bold yes)
			)
			(justify right bottom)
		)
	)
	(text "L"
		(exclude_from_sim no)
		(at 160.02 102.235 0)
		(effects
			(font
				(size 1.27 1.27)
			)
			(justify left bottom)
		)
	)
	(text "Naming of the LED signals is relative to the USB interface"
		(exclude_from_sim no)
		(at 87.63 184.785 0)
		(effects
			(font
				(size 1.27 1.27)
			)
			(justify left bottom)
		)
	)
	(text "L"
		(exclude_from_sim no)
		(at 153.67 95.885 0)
		(effects
			(font
				(size 1.27 1.27)
			)
			(justify left bottom)
		)
	)
	(text "H"
		(exclude_from_sim no)
		(at 153.67 102.235 0)
		(effects
			(font
				(size 1.27 1.27)
			)
			(justify left bottom)
		)
	)
	(text "RX"
		(exclude_from_sim no)
		(at 106.68 196.215 0)
		(effects
			(font
				(size 1.27 1.27)
			)
			(justify left bottom)
		)
	)
	(text "CONFIGURATION"
		(exclude_from_sim no)
		(at 165.1 92.71 0)
		(effects
			(font
				(size 1.27 1.27)
				(thickness 0.254)
				(bold yes)
			)
			(justify left bottom)
		)
	)
	(text "USBC0"
		(exclude_from_sim no)
		(at 387.985 73.66 0)
		(effects
			(font
				(size 1.27 1.27)
				(thickness 0.254)
				(bold yes)
			)
			(justify left bottom)
		)
	)
	(text "H"
		(exclude_from_sim no)
		(at 160.02 99.06 0)
		(effects
			(font
				(size 1.27 1.27)
			)
			(justify left bottom)
		)
	)
	(text "Debug USB-C 3"
		(exclude_from_sim no)
		(at 288.29 190.5 0)
		(effects
			(font
				(size 4 4)
				(thickness 0.8)
				(bold yes)
			)
			(justify right bottom)
		)
	)
	(text "USB + 2 LANE DP"
		(exclude_from_sim no)
		(at 165.1 105.41 0)
		(effects
			(font
				(size 1.27 1.27)
			)
			(justify left bottom)
		)
	)
	(text "Level Shifter acting as an open-drain switch"
		(exclude_from_sim no)
		(at 100.33 259.08 0)
		(effects
			(font
				(size 1.27 1.27)
			)
			(justify left bottom)
		)
	)
	(text "L"
		(exclude_from_sim no)
		(at 153.67 99.06 0)
		(effects
			(font
				(size 1.27 1.27)
			)
			(justify left bottom)
		)
	)
	(text "USBC3"
		(exclude_from_sim no)
		(at 389.255 207.01 0)
		(effects
			(font
				(size 1.27 1.27)
				(thickness 0.254)
				(bold yes)
			)
			(justify left bottom)
		)
	)
	(text "CTL1"
		(exclude_from_sim no)
		(at 151.765 92.71 0)
		(effects
			(font
				(size 1.27 1.27)
				(thickness 0.254)
				(bold yes)
			)
			(justify left bottom)
		)
	)
	(text "CTL0"
		(exclude_from_sim no)
		(at 158.115 92.71 0)
		(effects
			(font
				(size 1.27 1.27)
				(thickness 0.254)
				(bold yes)
			)
			(justify left bottom)
		)
	)
	(text "USB ONLY"
		(exclude_from_sim no)
		(at 165.1 99.06 0)
		(effects
			(font
				(size 1.27 1.27)
			)
			(justify left bottom)
		)
	)
	(label "USB_FTDI_P"
		(at 26.67 210.82 0)
		(effects
			(font
				(size 1.27 1.27)
			)
			(justify left bottom)
		)
	)
	(label "USBC0_SBU_P"
		(at 238.76 132.08 0)
		(effects
			(font
				(size 1.27 1.27)
			)
			(justify left bottom)
		)
	)
	(label "PDC_CTL0"
		(at 90.17 44.45 0)
		(effects
			(font
				(size 1.27 1.27)
			)
			(justify left bottom)
		)
	)
	(label "FTDI_3V3"
		(at 66.04 172.72 180)
		(effects
			(font
				(size 1.27 1.27)
			)
			(justify right bottom)
		)
	)
	(label "PDC_ADCIN2"
		(at 40.64 76.2 0)
		(effects
			(font
				(size 1.27 1.27)
			)
			(justify left bottom)
		)
	)
	(label "PDC_I2C1_SDA"
		(at 156.21 245.11 180)
		(effects
			(font
				(size 1.27 1.27)
			)
			(justify right bottom)
		)
	)
	(label "PDC_LDO_3V3"
		(at 40.64 123.19 0)
		(effects
			(font
				(size 1.27 1.27)
			)
			(justify left bottom)
		)
	)
	(label "PDC_I2C1_SCL"
		(at 90.17 96.52 0)
		(effects
			(font
				(size 1.27 1.27)
			)
			(justify left bottom)
		)
	)
	(label "USBC0_FLIP"
		(at 132.08 41.91 180)
		(effects
			(font
				(size 1.27 1.27)
			)
			(justify right bottom)
		)
	)
	(label "USBC0_FLIP"
		(at 187.96 101.6 0)
		(effects
			(font
				(size 1.27 1.27)
			)
			(justify left bottom)
		)
	)
	(label "USBC0_DPEQ0"
		(at 237.49 154.94 0)
		(effects
			(font
				(size 1.27 1.27)
			)
			(justify left bottom)
		)
	)
	(label "DRAIN1"
		(at 285.75 88.9 0)
		(effects
			(font
				(size 1.27 1.27)
			)
			(justify left bottom)
		)
	)
	(label "FTDI_3V3"
		(at 83.82 232.41 0)
		(effects
			(font
				(size 1.27 1.27)
			)
			(justify left bottom)
		)
	)
	(label "USBC0_CTL1"
		(at 132.08 46.99 180)
		(effects
			(font
				(size 1.27 1.27)
			)
			(justify right bottom)
		)
	)
	(label "USBSS0_TX_C_P"
		(at 209.55 121.92 180)
		(effects
			(font
				(size 1.1 1.1)
			)
			(justify right bottom)
		)
	)
	(label "FTDI_3V3"
		(at 123.19 270.51 0)
		(effects
			(font
				(size 1.27 1.27)
			)
			(justify left bottom)
		)
	)
	(label "PDC_LDO_1V8"
		(at 45.72 36.83 180)
		(effects
			(font
				(size 1.27 1.27)
			)
			(justify right bottom)
		)
	)
	(label "USBC0_TX2_N"
		(at 238.76 124.46 0)
		(effects
			(font
				(size 1.27 1.27)
			)
			(justify left bottom)
		)
	)
	(label "USBC0_RX1_P"
		(at 238.76 99.06 0)
		(effects
			(font
				(size 1.27 1.27)
			)
			(justify left bottom)
		)
	)
	(label "USBSS0_TX_C_N"
		(at 209.55 124.46 180)
		(effects
			(font
				(size 1.1 1.1)
			)
			(justify right bottom)
		)
	)
	(label "~{PDC_CS}"
		(at 101.6 72.39 180)
		(effects
			(font
				(size 1.27 1.27)
			)
			(justify right bottom)
		)
	)
	(label "USBC0_RX1_N"
		(at 238.76 101.6 0)
		(effects
			(font
				(size 1.27 1.27)
			)
			(justify left bottom)
		)
	)
	(label "USBC_HPD"
		(at 173.99 172.72 0)
		(effects
			(font
				(size 1.27 1.27)
			)
			(justify left bottom)
		)
	)
	(label "FTDI_LED_TX"
		(at 77.47 219.71 0)
		(effects
			(font
				(size 1.27 1.27)
			)
			(justify left bottom)
		)
	)
	(label "USB_FTDI_N"
		(at 26.67 213.36 0)
		(effects
			(font
				(size 1.27 1.27)
			)
			(justify left bottom)
		)
	)
	(label "FTDI_CBUS3{slash}SCL"
		(at 72.39 247.65 0)
		(effects
			(font
				(size 1.27 1.27)
			)
			(justify left bottom)
		)
	)
	(label "USBC3_CC2"
		(at 361.95 214.63 0)
		(effects
			(font
				(size 1.27 1.27)
			)
			(justify left bottom)
		)
	)
	(label "USBC0_CONN_TX1_N"
		(at 292.1 109.22 0)
		(effects
			(font
				(size 1.27 1.27)
			)
			(justify left bottom)
		)
	)
	(label "PDC_LDO_3V3"
		(at 45.72 39.37 180)
		(effects
			(font
				(size 1.27 1.27)
			)
			(justify right bottom)
		)
	)
	(label "USBC3_5V_PEN"
		(at 106.68 86.36 180)
		(effects
			(font
				(size 1.27 1.27)
			)
			(justify right bottom)
		)
	)
	(label "USBC3_CC1"
		(at 285.75 232.41 0)
		(effects
			(font
				(size 1.27 1.27)
			)
			(justify left bottom)
		)
	)
	(label "USBC0_CONN_TX2_N"
		(at 292.1 124.46 0)
		(effects
			(font
				(size 1.27 1.27)
			)
			(justify left bottom)
		)
	)
	(label "PDC_RESET"
		(at 40.64 55.88 0)
		(effects
			(font
				(size 1.27 1.27)
			)
			(justify left bottom)
		)
	)
	(label "USBC3_D_P"
		(at 361.95 219.71 0)
		(effects
			(font
				(size 1.27 1.27)
			)
			(justify left bottom)
		)
	)
	(label "USBC0_SSEQ1"
		(at 237.49 152.4 0)
		(effects
			(font
				(size 1.27 1.27)
			)
			(justify left bottom)
		)
	)
	(label "FTDI_LED_RX"
		(at 43.18 259.08 0)
		(effects
			(font
				(size 1.27 1.27)
			)
			(justify left bottom)
		)
	)
	(label "USBC0_VBUS"
		(at 327.66 73.66 0)
		(effects
			(font
				(size 1.27 1.27)
			)
			(justify left bottom)
		)
	)
	(label "USB_FTDI_P"
		(at 314.96 219.71 0)
		(effects
			(font
				(size 1.27 1.27)
			)
			(justify left bottom)
		)
	)
	(label "USBC0_5V_PEN"
		(at 106.68 88.9 180)
		(effects
			(font
				(size 1.27 1.27)
			)
			(justify right bottom)
		)
	)
	(label "USBC0_TX1_P"
		(at 238.76 106.68 0)
		(effects
			(font
				(size 1.27 1.27)
			)
			(justify left bottom)
		)
	)
	(label "USBC0_5V_PEN"
		(at 257.81 53.34 0)
		(effects
			(font
				(size 1.27 1.27)
			)
			(justify left bottom)
		)
	)
	(label "PDC_FLIP"
		(at 90.17 41.91 0)
		(effects
			(font
				(size 1.27 1.27)
			)
			(justify left bottom)
		)
	)
	(label "USBC0_EQ1"
		(at 237.49 162.56 0)
		(effects
			(font
				(size 1.27 1.27)
			)
			(justify left bottom)
		)
	)
	(label "USBC0_CC1"
		(at 327.66 78.74 0)
		(effects
			(font
				(size 1.27 1.27)
			)
			(justify left bottom)
		)
	)
	(label "PDC_I2C2_SDA"
		(at 90.17 109.22 0)
		(effects
			(font
				(size 1.27 1.27)
			)
			(justify left bottom)
		)
	)
	(label "USBC0_SBU_N"
		(at 238.76 129.54 0)
		(effects
			(font
				(size 1.27 1.27)
			)
			(justify left bottom)
		)
	)
	(label "FTDI_CBUS3{slash}SCL"
		(at 90.17 222.25 180)
		(effects
			(font
				(size 1.27 1.27)
			)
			(justify right bottom)
		)
	)
	(label "PDC_I2C2_SDA"
		(at 107.95 128.27 0)
		(effects
			(font
				(size 1.27 1.27)
			)
			(justify left bottom)
		)
	)
	(label "FTDI_3V3"
		(at 118.11 270.51 180)
		(effects
			(font
				(size 1.27 1.27)
			)
			(justify right bottom)
		)
	)
	(label "FTDI_CBUS0{slash}SDA"
		(at 90.17 214.63 180)
		(effects
			(font
				(size 1.27 1.27)
			)
			(justify right bottom)
		)
	)
	(label "HPDIN"
		(at 204.47 172.72 0)
		(effects
			(font
				(size 1.27 1.27)
			)
			(justify left bottom)
		)
	)
	(label "USBC3_D_N"
		(at 285.75 237.49 0)
		(effects
			(font
				(size 1.27 1.27)
			)
			(justify left bottom)
		)
	)
	(label "PDC_I2C2_IRQn"
		(at 90.17 104.14 0)
		(effects
			(font
				(size 1.27 1.27)
			)
			(justify left bottom)
		)
	)
	(label "USBSS0_RX_C_N"
		(at 209.55 116.84 180)
		(effects
			(font
				(size 1.1 1.1)
			)
			(justify right bottom)
		)
	)
	(label "PDC_HPD2"
		(at 100.33 52.07 180)
		(effects
			(font
				(size 1.27 1.27)
			)
			(justify right bottom)
		)
	)
	(label "PDC_GPIO14"
		(at 90.17 81.28 0)
		(effects
			(font
				(size 1.27 1.27)
			)
			(justify left bottom)
		)
	)
	(label "FTDI_3V3"
		(at 139.7 242.57 180)
		(effects
			(font
				(size 1.27 1.27)
			)
			(justify right bottom)
		)
	)
	(label "FTDI_CBUS_EN"
		(at 62.23 243.84 180)
		(effects
			(font
				(size 1.27 1.27)
			)
			(justify right bottom)
		)
	)
	(label "PDC_GPIO15"
		(at 90.17 83.82 0)
		(effects
			(font
				(size 1.27 1.27)
			)
			(justify left bottom)
		)
	)
	(label "PDC_I2C2_SCL"
		(at 90.17 106.68 0)
		(effects
			(font
				(size 1.27 1.27)
			)
			(justify left bottom)
		)
	)
	(label "USBC0_CONN_TX1_P"
		(at 292.1 106.68 0)
		(effects
			(font
				(size 1.27 1.27)
			)
			(justify left bottom)
		)
	)
	(label "USBC0_RX2_P"
		(at 238.76 114.3 0)
		(effects
			(font
				(size 1.27 1.27)
			)
			(justify left bottom)
		)
	)
	(label "PDC_I2C1_IRQn"
		(at 90.17 93.98 0)
		(effects
			(font
				(size 1.27 1.27)
			)
			(justify left bottom)
		)
	)
	(label "USBC3_CC2"
		(at 285.75 240.03 0)
		(effects
			(font
				(size 1.27 1.27)
			)
			(justify left bottom)
		)
	)
	(label "USBC3_FLG"
		(at 199.39 209.55 0)
		(effects
			(font
				(size 1.27 1.27)
			)
			(justify left bottom)
		)
	)
	(label "USBC3_D_N"
		(at 361.95 222.25 0)
		(effects
			(font
				(size 1.27 1.27)
			)
			(justify left bottom)
		)
	)
	(label "USBC3_CC1"
		(at 361.95 212.09 0)
		(effects
			(font
				(size 1.27 1.27)
			)
			(justify left bottom)
		)
	)
	(label "FTDI_3V3"
		(at 16.51 217.17 0)
		(effects
			(font
				(size 1.27 1.27)
			)
			(justify left bottom)
		)
	)
	(label "PDC_MISO"
		(at 101.6 64.77 180)
		(effects
			(font
				(size 1.27 1.27)
			)
			(justify right bottom)
		)
	)
	(label "PDC_CTL1"
		(at 90.17 46.99 0)
		(effects
			(font
				(size 1.27 1.27)
			)
			(justify left bottom)
		)
	)
	(label "FTDI_3V3"
		(at 30.48 234.95 0)
		(effects
			(font
				(size 1.27 1.27)
			)
			(justify left bottom)
		)
	)
	(label "USBC0_CTL1"
		(at 187.96 106.68 0)
		(effects
			(font
				(size 1.27 1.27)
			)
			(justify left bottom)
		)
	)
	(label "DRAIN2"
		(at 195.58 267.97 0)
		(effects
			(font
				(size 1.27 1.27)
			)
			(justify left bottom)
		)
	)
	(label "PDC_ADCIN1"
		(at 40.64 64.77 0)
		(effects
			(font
				(size 1.27 1.27)
			)
			(justify left bottom)
		)
	)
	(label "USBSS0_RX_C_P"
		(at 209.55 114.3 180)
		(effects
			(font
				(size 1.1 1.1)
			)
			(justify right bottom)
		)
	)
	(label "USBC0_CONN_TX2_P"
		(at 292.1 121.92 0)
		(effects
			(font
				(size 1.27 1.27)
			)
			(justify left bottom)
		)
	)
	(label "FTDI_3V3"
		(at 101.6 242.57 0)
		(effects
			(font
				(size 1.27 1.27)
			)
			(justify left bottom)
		)
	)
	(label "FTDI_CBUS0{slash}SDA"
		(at 72.39 245.11 0)
		(effects
			(font
				(size 1.27 1.27)
			)
			(justify left bottom)
		)
	)
	(label "USBC0_CTL0"
		(at 132.08 44.45 180)
		(effects
			(font
				(size 1.27 1.27)
			)
			(justify right bottom)
		)
	)
	(label "USBC0_FLG"
		(at 257.81 50.8 0)
		(effects
			(font
				(size 1.27 1.27)
			)
			(justify left bottom)
		)
	)
	(label "PDC_I2C1_SCL"
		(at 156.21 247.65 180)
		(effects
			(font
				(size 1.27 1.27)
			)
			(justify right bottom)
		)
	)
	(label "USBC0_DPEQ1"
		(at 237.49 157.48 0)
		(effects
			(font
				(size 1.27 1.27)
			)
			(justify left bottom)
		)
	)
	(label "PDC_I2C3_SDA"
		(at 91.44 58.42 0)
		(effects
			(font
				(size 1.27 1.27)
			)
			(justify left bottom)
		)
	)
	(label "PDC_MOSI"
		(at 101.6 67.31 180)
		(effects
			(font
				(size 1.27 1.27)
			)
			(justify right bottom)
		)
	)
	(label "USBC3_VBUS"
		(at 26.67 172.72 0)
		(effects
			(font
				(size 1.27 1.27)
			)
			(justify left bottom)
		)
	)
	(label "USBC0_RX2_N"
		(at 238.76 116.84 0)
		(effects
			(font
				(size 1.27 1.27)
			)
			(justify left bottom)
		)
	)
	(label "USBC0_SSEQ0"
		(at 237.49 149.86 0)
		(effects
			(font
				(size 1.27 1.27)
			)
			(justify left bottom)
		)
	)
	(label "USBC0_CC2"
		(at 327.66 81.28 0)
		(effects
			(font
				(size 1.27 1.27)
			)
			(justify left bottom)
		)
	)
	(label "PDC_I2C1_SCL"
		(at 107.95 125.73 0)
		(effects
			(font
				(size 1.27 1.27)
			)
			(justify left bottom)
		)
	)
	(label "USBC3_5V_PEN"
		(at 170.18 218.44 0)
		(effects
			(font
				(size 1.27 1.27)
			)
			(justify left bottom)
		)
	)
	(label "PDC_I2C1_SDA"
		(at 90.17 99.06 0)
		(effects
			(font
				(size 1.27 1.27)
			)
			(justify left bottom)
		)
	)
	(label "FTDI_CBUS_EN"
		(at 96.52 250.19 0)
		(effects
			(font
				(size 1.27 1.27)
			)
			(justify left bottom)
		)
	)
	(label "PDC_I2C2_SCL"
		(at 107.95 130.81 0)
		(effects
			(font
				(size 1.27 1.27)
			)
			(justify left bottom)
		)
	)
	(label "USBC0_CTL0"
		(at 187.96 104.14 0)
		(effects
			(font
				(size 1.27 1.27)
			)
			(justify left bottom)
		)
	)
	(label "USB_FTDI_N"
		(at 314.96 222.25 0)
		(effects
			(font
				(size 1.27 1.27)
			)
			(justify left bottom)
		)
	)
	(label "USBC3_D_P"
		(at 285.75 234.95 0)
		(effects
			(font
				(size 1.27 1.27)
			)
			(justify left bottom)
		)
	)
	(label "USBC0_TX1_N"
		(at 238.76 109.22 0)
		(effects
			(font
				(size 1.27 1.27)
			)
			(justify left bottom)
		)
	)
	(label "FTDI_LED_RX"
		(at 77.47 217.17 0)
		(effects
			(font
				(size 1.27 1.27)
			)
			(justify left bottom)
		)
	)
	(label "USBC0_EQ0"
		(at 237.49 160.02 0)
		(effects
			(font
				(size 1.27 1.27)
			)
			(justify left bottom)
		)
	)
	(label "PDC_SCLK"
		(at 101.6 69.85 180)
		(effects
			(font
				(size 1.27 1.27)
			)
			(justify right bottom)
		)
	)
	(label "~{PDC_I2C3_IRQ}"
		(at 91.44 60.96 0)
		(effects
			(font
				(size 1.27 1.27)
			)
			(justify left bottom)
		)
	)
	(label "PDC_LDO_3V3"
		(at 12.7 64.77 0)
		(effects
			(font
				(size 1.27 1.27)
			)
			(justify left bottom)
		)
	)
	(label "PDC_I2C3_SCL"
		(at 91.44 55.88 0)
		(effects
			(font
				(size 1.27 1.27)
			)
			(justify left bottom)
		)
	)
	(label "USBC0_TX2_P"
		(at 238.76 121.92 0)
		(effects
			(font
				(size 1.27 1.27)
			)
			(justify left bottom)
		)
	)
	(label "PDC_I2C1_SDA"
		(at 107.95 123.19 0)
		(effects
			(font
				(size 1.27 1.27)
			)
			(justify left bottom)
		)
	)
	(label "USBC3_VBUS"
		(at 361.95 207.01 0)
		(effects
			(font
				(size 1.27 1.27)
			)
			(justify left bottom)
		)
	)
	(label "USBC0_I2C_EN"
		(at 237.49 147.32 0)
		(effects
			(font
				(size 1.27 1.27)
			)
			(justify left bottom)
		)
	)
	(global_label "PDC_MISO"
		(shape output)
		(at 38.1 137.16 180)
		(effects
			(font
				(size 1.27 1.27)
			)
			(justify right)
		)
		(property "Intersheetrefs" "${INTERSHEET_REFS}"
			(at 22.225 137.16 0)
			(effects
				(font
					(size 1.27 1.27)
				)
				(justify right)
			)
		)
	)
	(global_label "SYS_SCL"
		(shape input)
		(at 199.39 82.55 180)
		(effects
			(font
				(size 1.27 1.27)
			)
			(justify right)
		)
		(property "Intersheetrefs" "${INTERSHEET_REFS}"
			(at 187.96 82.55 0)
			(effects
				(font
					(size 1 1)
				)
				(justify right)
			)
		)
	)
	(global_label "EEPROM_PWR"
		(shape input)
		(at 38.1 139.7 180)
		(effects
			(font
				(size 1.27 1.27)
			)
			(justify right)
		)
		(property "Intersheetrefs" "${INTERSHEET_REFS}"
			(at 22.225 139.7 0)
			(effects
				(font
					(size 1.27 1.27)
				)
				(justify right)
			)
		)
	)
	(global_label "EEPROM_PWR"
		(shape input)
		(at 38.1 142.24 180)
		(effects
			(font
				(size 1.27 1.27)
			)
			(justify right)
		)
		(property "Intersheetrefs" "${INTERSHEET_REFS}"
			(at 22.225 142.24 0)
			(effects
				(font
					(size 1.27 1.27)
				)
				(justify right)
			)
		)
	)
	(global_label "DP1_TXD0_N"
		(shape input)
		(at 204.47 142.24 180)
		(effects
			(font
				(size 1.27 1.27)
			)
			(justify right)
		)
		(property "Intersheetrefs" "${INTERSHEET_REFS}"
			(at 188.595 142.24 0)
			(effects
				(font
					(size 1.1 1.1)
				)
				(justify right)
			)
		)
	)
	(global_label "USB2_D_P"
		(shape input)
		(at 342.9 91.44 180)
		(effects
			(font
				(size 1.27 1.27)
			)
			(justify right)
		)
		(property "Intersheetrefs" "${INTERSHEET_REFS}"
			(at 330.2 91.44 0)
			(effects
				(font
					(size 1.27 1.27)
				)
				(justify right)
			)
		)
	)
	(global_label "GPIO010"
		(shape output)
		(at 121.92 93.98 0)
		(effects
			(font
				(size 1.27 1.27)
			)
			(justify left)
		)
		(property "Intersheetrefs" "${INTERSHEET_REFS}"
			(at 132.715 93.98 0)
			(effects
				(font
					(size 1.27 1.27)
				)
				(justify left)
			)
		)
	)
	(global_label "DP1_TXD2_N"
		(shape input)
		(at 204.47 157.48 180)
		(effects
			(font
				(size 1.27 1.27)
			)
			(justify right)
		)
		(property "Intersheetrefs" "${INTERSHEET_REFS}"
			(at 188.595 157.48 0)
			(effects
				(font
					(size 1.1 1.1)
				)
				(justify right)
			)
		)
	)
	(global_label "PDC_SCLK"
		(shape input)
		(at 38.1 144.78 180)
		(effects
			(font
				(size 1.27 1.27)
			)
			(justify right)
		)
		(property "Intersheetrefs" "${INTERSHEET_REFS}"
			(at 22.225 144.78 0)
			(effects
				(font
					(size 1.27 1.27)
				)
				(justify right)
			)
		)
	)
	(global_label "DP1_AUX_N"
		(shape input)
		(at 168.91 144.78 180)
		(effects
			(font
				(size 1.27 1.27)
			)
			(justify right)
		)
		(property "Intersheetrefs" "${INTERSHEET_REFS}"
			(at 153.035 144.78 0)
			(effects
				(font
					(size 1.1 1.1)
				)
				(justify right)
			)
		)
	)
	(global_label "DP1_TXD3_P"
		(shape input)
		(at 204.47 162.56 180)
		(effects
			(font
				(size 1.27 1.27)
			)
			(justify right)
		)
		(property "Intersheetrefs" "${INTERSHEET_REFS}"
			(at 188.595 162.56 0)
			(effects
				(font
					(size 1.1 1.1)
				)
				(justify right)
			)
		)
	)
	(global_label "SYS_SDA"
		(shape bidirectional)
		(at 199.39 85.09 180)
		(effects
			(font
				(size 1.27 1.27)
			)
			(justify right)
		)
		(property "Intersheetrefs" "${INTERSHEET_REFS}"
			(at 187.96 85.09 0)
			(effects
				(font
					(size 1 1)
				)
				(justify right)
			)
		)
	)
	(global_label "USBSS0_TX_P"
		(shape input)
		(at 171.45 121.92 180)
		(effects
			(font
				(size 1.27 1.27)
			)
			(justify right)
		)
		(property "Intersheetrefs" "${INTERSHEET_REFS}"
			(at 155.575 121.92 0)
			(effects
				(font
					(size 1.1 1.1)
				)
				(justify right)
			)
		)
	)
	(global_label "PWR_SOFT"
		(shape output)
		(at 83.82 207.01 0)
		(effects
			(font
				(size 1.27 1.27)
			)
			(justify left)
		)
		(property "Intersheetrefs" "${INTERSHEET_REFS}"
			(at 95.885 207.01 0)
			(effects
				(font
					(size 1.27 1.27)
				)
				(justify left)
			)
		)
	)
	(global_label "DEBUG_TXD"
		(shape input)
		(at 83.82 204.47 0)
		(effects
			(font
				(size 1.27 1.27)
			)
			(justify left)
		)
		(property "Intersheetrefs" "${INTERSHEET_REFS}"
			(at 97.79 204.47 0)
			(effects
				(font
					(size 1.27 1.27)
				)
				(justify left)
			)
		)
	)
	(global_label "~{RESET}"
		(shape bidirectional)
		(at 30.48 251.46 180)
		(fields_autoplaced yes)
		(effects
			(font
				(size 1.27 1.27)
			)
			(justify right)
		)
		(property "Intersheetrefs" "${INTERSHEET_REFS}"
			(at 20.6384 251.46 0)
			(effects
				(font
					(size 1.27 1.27)
				)
				(justify right)
			)
		)
	)
	(global_label "DP1_AUX_P"
		(shape input)
		(at 168.91 147.32 180)
		(effects
			(font
				(size 1.27 1.27)
			)
			(justify right)
		)
		(property "Intersheetrefs" "${INTERSHEET_REFS}"
			(at 153.035 147.32 0)
			(effects
				(font
					(size 1.1 1.1)
				)
				(justify right)
			)
		)
	)
	(global_label "USBSS0_TX_N"
		(shape input)
		(at 171.45 124.46 180)
		(effects
			(font
				(size 1.27 1.27)
			)
			(justify right)
		)
		(property "Intersheetrefs" "${INTERSHEET_REFS}"
			(at 155.575 124.46 0)
			(effects
				(font
					(size 1.1 1.1)
				)
				(justify right)
			)
		)
	)
	(global_label "DP1_TXD2_P"
		(shape input)
		(at 204.47 154.94 180)
		(effects
			(font
				(size 1.27 1.27)
			)
			(justify right)
		)
		(property "Intersheetrefs" "${INTERSHEET_REFS}"
			(at 188.595 154.94 0)
			(effects
				(font
					(size 1.1 1.1)
				)
				(justify right)
			)
		)
	)
	(global_label "SYS_SDA"
		(shape bidirectional)
		(at 121.92 99.06 0)
		(effects
			(font
				(size 1.27 1.27)
			)
			(justify left)
		)
		(property "Intersheetrefs" "${INTERSHEET_REFS}"
			(at 133.35 99.06 0)
			(effects
				(font
					(size 1 1)
				)
				(justify left)
			)
		)
	)
	(global_label "DEBUG_RXD"
		(shape output)
		(at 83.82 201.93 0)
		(effects
			(font
				(size 1.27 1.27)
			)
			(justify left)
		)
		(property "Intersheetrefs" "${INTERSHEET_REFS}"
			(at 97.79 201.93 0)
			(effects
				(font
					(size 1.27 1.27)
				)
				(justify left)
			)
		)
	)
	(global_label "USBSS0_RX_P"
		(shape output)
		(at 171.45 114.3 180)
		(effects
			(font
				(size 1.27 1.27)
			)
			(justify right)
		)
		(property "Intersheetrefs" "${INTERSHEET_REFS}"
			(at 155.575 114.3 0)
			(effects
				(font
					(size 1.1 1.1)
				)
				(justify right)
			)
		)
	)
	(global_label "DP1_TXD3_N"
		(shape input)
		(at 204.47 165.1 180)
		(effects
			(font
				(size 1.27 1.27)
			)
			(justify right)
		)
		(property "Intersheetrefs" "${INTERSHEET_REFS}"
			(at 188.595 165.1 0)
			(effects
				(font
					(size 1.1 1.1)
				)
				(justify right)
			)
		)
	)
	(global_label "EEPROM_PWR"
		(shape input)
		(at 77.47 123.19 0)
		(effects
			(font
				(size 1.27 1.27)
			)
			(justify left)
		)
		(property "Intersheetrefs" "${INTERSHEET_REFS}"
			(at 93.345 123.19 0)
			(effects
				(font
					(size 1.27 1.27)
				)
				(justify left)
			)
		)
	)
	(global_label "DP1_TXD1_N"
		(shape input)
		(at 204.47 149.86 180)
		(effects
			(font
				(size 1.27 1.27)
			)
			(justify right)
		)
		(property "Intersheetrefs" "${INTERSHEET_REFS}"
			(at 188.595 149.86 0)
			(effects
				(font
					(size 1.1 1.1)
				)
				(justify right)
			)
		)
	)
	(global_label "PDC_MOSI"
		(shape input)
		(at 38.1 134.62 180)
		(effects
			(font
				(size 1.27 1.27)
			)
			(justify right)
		)
		(property "Intersheetrefs" "${INTERSHEET_REFS}"
			(at 22.225 134.62 0)
			(effects
				(font
					(size 1.27 1.27)
				)
				(justify right)
			)
		)
	)
	(global_label "USBSS0_RX_N"
		(shape output)
		(at 171.45 116.84 180)
		(effects
			(font
				(size 1.27 1.27)
			)
			(justify right)
		)
		(property "Intersheetrefs" "${INTERSHEET_REFS}"
			(at 155.575 116.84 0)
			(effects
				(font
					(size 1.1 1.1)
				)
				(justify right)
			)
		)
	)
	(global_label "DP1_TXD0_P"
		(shape input)
		(at 204.47 139.7 180)
		(effects
			(font
				(size 1.27 1.27)
			)
			(justify right)
		)
		(property "Intersheetrefs" "${INTERSHEET_REFS}"
			(at 188.595 139.7 0)
			(effects
				(font
					(size 1.1 1.1)
				)
				(justify right)
			)
		)
	)
	(global_label "USBC_HPD"
		(shape output)
		(at 120.65 52.07 0)
		(effects
			(font
				(size 1.27 1.27)
			)
			(justify left)
		)
		(property "Intersheetrefs" "${INTERSHEET_REFS}"
			(at 132.715 52.07 0)
			(effects
				(font
					(size 1.27 1.27)
				)
				(justify left)
			)
		)
	)
	(global_label "USBPD1_HV"
		(shape bidirectional)
		(at 185.42 241.3 180)
		(effects
			(font
				(size 1.27 1.27)
			)
			(justify right)
		)
		(property "Intersheetrefs" "${INTERSHEET_REFS}"
			(at 170.18 241.3 0)
			(effects
				(font
					(size 1.27 1.27)
				)
				(justify right)
			)
		)
	)
	(global_label "DP1_TXD1_P"
		(shape input)
		(at 204.47 147.32 180)
		(effects
			(font
				(size 1.27 1.27)
			)
			(justify right)
		)
		(property "Intersheetrefs" "${INTERSHEET_REFS}"
			(at 188.595 147.32 0)
			(effects
				(font
					(size 1.1 1.1)
				)
				(justify right)
			)
		)
	)
	(global_label "USBPD2_HV"
		(shape bidirectional)
		(at 260.35 60.96 180)
		(effects
			(font
				(size 1.27 1.27)
			)
			(justify right)
		)
		(property "Intersheetrefs" "${INTERSHEET_REFS}"
			(at 245.11 60.96 0)
			(effects
				(font
					(size 1.27 1.27)
				)
				(justify right)
			)
		)
	)
	(global_label "USB2_D_N"
		(shape input)
		(at 342.9 93.98 180)
		(effects
			(font
				(size 1.27 1.27)
			)
			(justify right)
		)
		(property "Intersheetrefs" "${INTERSHEET_REFS}"
			(at 330.2 93.98 0)
			(effects
				(font
					(size 1.27 1.27)
				)
				(justify right)
			)
		)
	)
	(global_label "~{PDC_CS}"
		(shape input)
		(at 38.1 147.32 180)
		(effects
			(font
				(size 1.27 1.27)
			)
			(justify right)
		)
		(property "Intersheetrefs" "${INTERSHEET_REFS}"
			(at 22.225 147.32 0)
			(effects
				(font
					(size 1.27 1.27)
				)
				(justify right)
			)
		)
	)
	(global_label "USBC0_FLG"
		(shape output)
		(at 250.19 50.8 180)
		(effects
			(font
				(size 1.27 1.27)
			)
			(justify right)
		)
		(property "Intersheetrefs" "${INTERSHEET_REFS}"
			(at 236.22 50.8 0)
			(effects
				(font
					(size 1.27 1.27)
				)
				(justify right)
			)
		)
	)
	(global_label "SYS_SCL"
		(shape input)
		(at 121.92 96.52 0)
		(effects
			(font
				(size 1.27 1.27)
			)
			(justify left)
		)
		(property "Intersheetrefs" "${INTERSHEET_REFS}"
			(at 133.35 96.52 0)
			(effects
				(font
					(size 1 1)
				)
				(justify left)
			)
		)
	)
	(symbol
		(lib_name "R_4k7_0402_1")
		(lib_id "antmicroResistors0402:R_4k7_0402")
		(at 132.08 130.81 180)
		(unit 1)
		(exclude_from_sim no)
		(in_bom yes)
		(on_board yes)
		(dnp no)
		(property "Reference" "R130"
			(at 132.08 130.175 0)
			(effects
				(font
					(size 1.27 1.27)
				)
				(justify right top)
			)
		)
		(property "Value" "R_4k7_0402"
			(at 111.76 118.11 0)
			(effects
				(font
					(size 1.27 1.27)
					(thickness 0.15)
				)
				(justify left bottom)
				(hide yes)
			)
		)
		(property "Footprint" "antmicro-footprints:R_0402_1005Metric"
			(at 111.76 115.57 0)
			(effects
				(font
					(size 1.27 1.27)
					(thickness 0.15)
				)
				(justify left bottom)
				(hide yes)
			)
		)
		(property "Datasheet" "https://www.bourns.com/docs/product-datasheets/cr.pdf"
			(at 111.76 113.03 0)
			(effects
				(font
					(size 1.27 1.27)
					(thickness 0.15)
				)
				(justify left bottom)
				(hide yes)
			)
		)
		(property "Description" ""
			(at 132.08 130.81 0)
			(effects
				(font
					(size 1.27 1.27)
				)
				(hide yes)
			)
		)
		(property "Manufacturer" "Bourns"
			(at 111.76 107.95 0)
			(effects
				(font
					(size 1.27 1.27)
					(thickness 0.15)
				)
				(justify left bottom)
				(hide yes)
			)
		)
		(property "MPN" "CR0402-FX-4701GLF"
			(at 111.76 110.49 0)
			(effects
				(font
					(size 1.27 1.27)
					(thickness 0.15)
				)
				(justify left bottom)
				(hide yes)
			)
		)
		(property "Val" "4k7"
			(at 123.19 130.175 0)
			(effects
				(font
					(size 1.27 1.27)
					(thickness 0.15)
				)
				(justify right top)
			)
		)
		(property "License" "Apache-2.0"
			(at 111.76 105.41 0)
			(effects
				(font
					(size 1.27 1.27)
					(thickness 0.15)
				)
				(justify left bottom)
				(hide yes)
			)
		)
		(property "Author" "Antmicro"
			(at 111.76 102.87 0)
			(effects
				(font
					(size 1.27 1.27)
					(thickness 0.15)
				)
				(justify left bottom)
				(hide yes)
			)
		)
		(property "Tolerance" "1%"
			(at 111.76 120.65 0)
			(effects
				(font
					(size 1.27 1.27)
				)
				(justify left bottom)
				(hide yes)
			)
		)
		(pin "1"
		)
		(pin "2"
		)
		(instances
			(project "jetson-orin-baseboard"
				(path ""
					(reference "R130")
					(unit 1)
				)
			)
		)
	)
	(symbol
		(lib_id "antmicroTVSDiodes:TPD4E05U06QDQARQ1")
		(at 323.85 135.89 270)
		(unit 1)
		(exclude_from_sim no)
		(in_bom yes)
		(on_board yes)
		(dnp no)
		(fields_autoplaced yes)
		(property "Reference" "U14"
			(at 319.405 147.32 90)
			(effects
				(font
					(size 1.27 1.27)
				)
			)
		)
		(property "Value" "TPD4E05U06QDQARQ1"
			(at 313.69 160.02 0)
			(effects
				(font
					(size 1.27 1.27)
					(thickness 0.15)
				)
				(justify left bottom)
				(hide yes)
			)
		)
		(property "Footprint" "antmicro-footprints:USON-10_2.5x1mm_P0.5mm"
			(at 318.77 160.02 0)
			(effects
				(font
					(size 1.27 1.27)
					(thickness 0.15)
				)
				(justify left bottom)
				(hide yes)
			)
		)
		(property "Datasheet" "https://www.ti.com/lit/ds/symlink/tpd4e05u06-q1.pdf?HQS=dis-mous-null-mousermode-dsf-pf-null-wwe&ts=1663591265741&ref_url=https%253A%252F%252Fwww.mouser.com%252F"
			(at 316.23 160.02 0)
			(effects
				(font
					(size 1.27 1.27)
					(thickness 0.15)
				)
				(justify left bottom)
				(hide yes)
			)
		)
		(property "Description" ""
			(at 323.85 135.89 0)
			(effects
				(font
					(size 1.27 1.27)
				)
				(hide yes)
			)
		)
		(property "Manufacturer" "Texas Instruments"
			(at 311.15 160.02 0)
			(effects
				(font
					(size 1.27 1.27)
					(thickness 0.15)
				)
				(justify left bottom)
				(hide yes)
			)
		)
		(property "MPN" "TPD4E05U06QDQARQ1"
			(at 319.405 149.86 90)
			(effects
				(font
					(size 1.27 1.27)
					(thickness 0.15)
				)
			)
		)
		(property "Author" "Antmicro"
			(at 308.61 160.02 0)
			(effects
				(font
					(size 1.27 1.27)
					(thickness 0.15)
				)
				(justify left bottom)
				(hide yes)
			)
		)
		(property "License" "Apache-2.0"
			(at 306.07 160.02 0)
			(effects
				(font
					(size 1.27 1.27)
					(thickness 0.15)
				)
				(justify left bottom)
				(hide yes)
			)
		)
		(pin "1"
		)
		(pin "10"
		)
		(pin "2"
		)
		(pin "3"
		)
		(pin "4"
		)
		(pin "5"
		)
		(pin "6"
		)
		(pin "7"
		)
		(pin "8"
		)
		(pin "9"
		)
		(instances
			(project "jetson-orin-baseboard"
				(path ""
					(reference "U14")
					(unit 1)
				)
			)
		)
	)
	(symbol
		(lib_name "R_0R_0402_6")
		(lib_id "antmicroResistors0402:R_0R_0402")
		(at 78.74 207.01 0)
		(mirror y)
		(unit 1)
		(exclude_from_sim no)
		(in_bom no)
		(on_board yes)
		(dnp yes)
		(property "Reference" "R58"
			(at 78.74 206.375 0)
			(effects
				(font
					(size 1.27 1.27)
				)
				(justify right bottom)
			)
		)
		(property "Value" "R_0R_0402"
			(at 58.42 219.71 0)
			(effects
				(font
					(size 1.27 1.27)
					(thickness 0.15)
				)
				(justify left bottom)
				(hide yes)
			)
		)
		(property "Footprint" "antmicro-footprints:R_0402_1005Metric"
			(at 58.42 222.25 0)
			(effects
				(font
					(size 1.27 1.27)
					(thickness 0.15)
				)
				(justify left bottom)
				(hide yes)
			)
		)
		(property "Datasheet" "https://industrial.panasonic.com/cdbs/www-data/pdf/RDA0000/AOA0000C301.pdf"
			(at 58.42 224.79 0)
			(effects
				(font
					(size 1.27 1.27)
					(thickness 0.15)
				)
				(justify left bottom)
				(hide yes)
			)
		)
		(property "Description" ""
			(at 78.74 207.01 0)
			(effects
				(font
					(size 1.27 1.27)
				)
				(hide yes)
			)
		)
		(property "Manufacturer" "Panasonic"
			(at 58.42 229.87 0)
			(effects
				(font
					(size 1.27 1.27)
					(thickness 0.15)
				)
				(justify left bottom)
				(hide yes)
			)
		)
		(property "MPN" "ERJ2GE0R00X"
			(at 58.42 227.33 0)
			(effects
				(font
					(size 1.27 1.27)
					(thickness 0.15)
				)
				(justify left bottom)
				(hide yes)
			)
		)
		(property "Val" "0R"
			(at 71.12 206.375 0)
			(effects
				(font
					(size 1.27 1.27)
					(thickness 0.15)
				)
				(justify right bottom)
			)
		)
		(property "License" "Apache-2.0"
			(at 58.42 232.41 0)
			(effects
				(font
					(size 1.27 1.27)
					(thickness 0.15)
				)
				(justify left bottom)
				(hide yes)
			)
		)
		(property "Author" "Antmicro"
			(at 58.42 234.95 0)
			(effects
				(font
					(size 1.27 1.27)
					(thickness 0.15)
				)
				(justify left bottom)
				(hide yes)
			)
		)
		(property "Tolerance" "~"
			(at 58.42 217.17 0)
			(effects
				(font
					(size 1.27 1.27)
				)
				(justify left bottom)
				(hide yes)
			)
		)
		(property "Current" "1A"
			(at 58.42 237.49 0)
			(effects
				(font
					(size 1.27 1.27)
					(thickness 0.15)
				)
				(justify left bottom)
				(hide yes)
			)
		)
		(pin "1"
		)
		(pin "2"
		)
		(instances
			(project "jetson-orin-baseboard"
				(path ""
					(reference "R58")
					(unit 1)
				)
			)
		)
	)
	(symbol
		(lib_id "antmicroResistors0402:R_1k_0402")
		(at 262.89 147.32 0)
		(unit 1)
		(exclude_from_sim no)
		(in_bom no)
		(on_board yes)
		(dnp yes)
		(property "Reference" "R88"
			(at 268.605 146.685 0)
			(effects
				(font
					(size 1.27 1.27)
				)
				(justify left bottom)
			)
		)
		(property "Value" "R_1k_0402"
			(at 283.21 160.02 0)
			(effects
				(font
					(size 1.27 1.27)
					(thickness 0.15)
				)
				(justify left bottom)
				(hide yes)
			)
		)
		(property "Footprint" "antmicro-footprints:R_0402_1005Metric"
			(at 283.21 162.56 0)
			(effects
				(font
					(size 1.27 1.27)
					(thickness 0.15)
				)
				(justify left bottom)
				(hide yes)
			)
		)
		(property "Datasheet" "https://www.bourns.com/docs/product-datasheets/cr.pdf"
			(at 283.21 165.1 0)
			(effects
				(font
					(size 1.27 1.27)
					(thickness 0.15)
				)
				(justify left bottom)
				(hide yes)
			)
		)
		(property "Description" ""
			(at 262.89 147.32 0)
			(effects
				(font
					(size 1.27 1.27)
				)
				(hide yes)
			)
		)
		(property "Manufacturer" "Bourns"
			(at 283.21 170.18 0)
			(effects
				(font
					(size 1.27 1.27)
					(thickness 0.15)
				)
				(justify left bottom)
				(hide yes)
			)
		)
		(property "MPN" "CR0402-FX-1001GLF"
			(at 283.21 167.64 0)
			(effects
				(font
					(size 1.27 1.27)
					(thickness 0.15)
				)
				(justify left bottom)
				(hide yes)
			)
		)
		(property "Val" "1k"
			(at 260.35 146.685 0)
			(effects
				(font
					(size 1.27 1.27)
					(thickness 0.15)
				)
				(justify left bottom)
			)
		)
		(property "License" "Apache-2.0"
			(at 283.21 172.72 0)
			(effects
				(font
					(size 1.27 1.27)
					(thickness 0.15)
				)
				(justify left bottom)
				(hide yes)
			)
		)
		(property "Author" "Antmicro"
			(at 283.21 175.26 0)
			(effects
				(font
					(size 1.27 1.27)
					(thickness 0.15)
				)
				(justify left bottom)
				(hide yes)
			)
		)
		(property "Tolerance" "1%"
			(at 283.21 157.48 0)
			(effects
				(font
					(size 1.27 1.27)
				)
				(justify left bottom)
				(hide yes)
			)
		)
		(pin "1"
		)
		(pin "2"
		)
		(instances
			(project "jetson-orin-baseboard"
				(path ""
					(reference "R88")
					(unit 1)
				)
			)
		)
	)
	(symbol
		(lib_name "R_4k7_0402_2")
		(lib_id "antmicroResistors0402:R_4k7_0402")
		(at 132.08 123.19 180)
		(unit 1)
		(exclude_from_sim no)
		(in_bom yes)
		(on_board yes)
		(dnp no)
		(property "Reference" "R246"
			(at 132.08 122.555 0)
			(effects
				(font
					(size 1.27 1.27)
				)
				(justify right top)
			)
		)
		(property "Value" "R_4k7_0402"
			(at 111.76 110.49 0)
			(effects
				(font
					(size 1.27 1.27)
					(thickness 0.15)
				)
				(justify left bottom)
				(hide yes)
			)
		)
		(property "Footprint" "antmicro-footprints:R_0402_1005Metric"
			(at 111.76 107.95 0)
			(effects
				(font
					(size 1.27 1.27)
					(thickness 0.15)
				)
				(justify left bottom)
				(hide yes)
			)
		)
		(property "Datasheet" "https://www.bourns.com/docs/product-datasheets/cr.pdf"
			(at 111.76 105.41 0)
			(effects
				(font
					(size 1.27 1.27)
					(thickness 0.15)
				)
				(justify left bottom)
				(hide yes)
			)
		)
		(property "Description" ""
			(at 132.08 123.19 0)
			(effects
				(font
					(size 1.27 1.27)
				)
				(hide yes)
			)
		)
		(property "Manufacturer" "Bourns"
			(at 111.76 100.33 0)
			(effects
				(font
					(size 1.27 1.27)
					(thickness 0.15)
				)
				(justify left bottom)
				(hide yes)
			)
		)
		(property "MPN" "CR0402-FX-4701GLF"
			(at 111.76 102.87 0)
			(effects
				(font
					(size 1.27 1.27)
					(thickness 0.15)
				)
				(justify left bottom)
				(hide yes)
			)
		)
		(property "Val" "4k7"
			(at 123.19 122.555 0)
			(effects
				(font
					(size 1.27 1.27)
					(thickness 0.15)
				)
				(justify right top)
			)
		)
		(property "License" "Apache-2.0"
			(at 111.76 97.79 0)
			(effects
				(font
					(size 1.27 1.27)
					(thickness 0.15)
				)
				(justify left bottom)
				(hide yes)
			)
		)
		(property "Author" "Antmicro"
			(at 111.76 95.25 0)
			(effects
				(font
					(size 1.27 1.27)
					(thickness 0.15)
				)
				(justify left bottom)
				(hide yes)
			)
		)
		(property "Tolerance" "1%"
			(at 111.76 113.03 0)
			(effects
				(font
					(size 1.27 1.27)
				)
				(justify left bottom)
				(hide yes)
			)
		)
		(pin "1"
		)
		(pin "2"
		)
		(instances
			(project "jetson-orin-baseboard"
				(path ""
					(reference "R246")
					(unit 1)
				)
			)
		)
	)
	(symbol
		(lib_name "R_100k_0402_1")
		(lib_id "antmicroResistors0402:R_100k_0402")
		(at 30.48 78.74 0)
		(unit 1)
		(exclude_from_sim no)
		(in_bom yes)
		(on_board yes)
		(dnp no)
		(property "Reference" "R45"
			(at 35.56 78.105 0)
			(effects
				(font
					(size 1.27 1.27)
				)
				(justify left bottom)
			)
		)
		(property "Value" "R_100k_0402"
			(at 50.8 91.44 0)
			(effects
				(font
					(size 1.27 1.27)
					(thickness 0.15)
				)
				(justify left bottom)
				(hide yes)
			)
		)
		(property "Footprint" "antmicro-footprints:R_0402_1005Metric"
			(at 50.8 93.98 0)
			(effects
				(font
					(size 1.27 1.27)
					(thickness 0.15)
				)
				(justify left bottom)
				(hide yes)
			)
		)
		(property "Datasheet" "https://www.bourns.com/docs/product-datasheets/cr.pdf"
			(at 50.8 96.52 0)
			(effects
				(font
					(size 1.27 1.27)
					(thickness 0.15)
				)
				(justify left bottom)
				(hide yes)
			)
		)
		(property "Description" ""
			(at 30.48 78.74 0)
			(effects
				(font
					(size 1.27 1.27)
				)
				(hide yes)
			)
		)
		(property "Manufacturer" "Bourns"
			(at 50.8 101.6 0)
			(effects
				(font
					(size 1.27 1.27)
					(thickness 0.15)
				)
				(justify left bottom)
				(hide yes)
			)
		)
		(property "MPN" "CR0402-FX-1003GLF"
			(at 50.8 99.06 0)
			(effects
				(font
					(size 1.27 1.27)
					(thickness 0.15)
				)
				(justify left bottom)
				(hide yes)
			)
		)
		(property "Val" "100k"
			(at 26.035 78.105 0)
			(effects
				(font
					(size 1.27 1.27)
					(thickness 0.15)
				)
				(justify left bottom)
			)
		)
		(property "License" "Apache-2.0"
			(at 50.8 104.14 0)
			(effects
				(font
					(size 1.27 1.27)
					(thickness 0.15)
				)
				(justify left bottom)
				(hide yes)
			)
		)
		(property "Author" "Antmicro"
			(at 50.8 106.68 0)
			(effects
				(font
					(size 1.27 1.27)
					(thickness 0.15)
				)
				(justify left bottom)
				(hide yes)
			)
		)
		(property "Tolerance" "1%"
			(at 50.8 88.9 0)
			(effects
				(font
					(size 1.27 1.27)
				)
				(justify left bottom)
				(hide yes)
			)
		)
		(pin "1"
		)
		(pin "2"
		)
		(instances
			(project "jetson-orin-baseboard"
				(path ""
					(reference "R45")
					(unit 1)
				)
			)
		)
	)
	(symbol
		(lib_name "GND_3")
		(lib_id "antmicropower:GND")
		(at 372.11 245.11 0)
		(mirror y)
		(unit 1)
		(exclude_from_sim no)
		(in_bom yes)
		(on_board yes)
		(dnp no)
		(property "Reference" "#PWR094"
			(at 372.11 251.46 0)
			(effects
				(font
					(size 1.27 1.27)
				)
				(justify left bottom)
				(hide yes)
			)
		)
		(property "Value" "GND"
			(at 372.11 248.92 0)
			(effects
				(font
					(size 1.27 1.27)
					(thickness 0.15)
				)
			)
		)
		(property "Footprint" ""
			(at 363.22 252.73 0)
			(effects
				(font
					(size 1.27 1.27)
					(thickness 0.15)
				)
				(justify left bottom)
				(hide yes)
			)
		)
		(property "Datasheet" ""
			(at 363.22 257.81 0)
			(effects
				(font
					(size 1.27 1.27)
					(thickness 0.15)
				)
				(justify left bottom)
				(hide yes)
			)
		)
		(property "Description" ""
			(at 372.11 245.11 0)
			(effects
				(font
					(size 1.27 1.27)
				)
				(hide yes)
			)
		)
		(property "Author" "Antmicro"
			(at 363.22 252.73 0)
			(effects
				(font
					(size 1.27 1.27)
					(thickness 0.15)
				)
				(justify left bottom)
				(hide yes)
			)
		)
		(property "License" "Apache-2.0"
			(at 363.22 255.27 0)
			(effects
				(font
					(size 1.27 1.27)
					(thickness 0.15)
				)
				(justify left bottom)
				(hide yes)
			)
		)
		(pin "1"
		)
		(instances
			(project "jetson-orin-baseboard"
				(path ""
					(reference "#PWR094")
					(unit 1)
				)
			)
		)
	)
	(symbol
		(lib_id "antmicroResistors0402:R_1k_0402")
		(at 262.89 172.72 0)
		(unit 1)
		(exclude_from_sim no)
		(in_bom yes)
		(on_board yes)
		(dnp no)
		(property "Reference" "R98"
			(at 268.605 172.085 0)
			(effects
				(font
					(size 1.27 1.27)
				)
				(justify left bottom)
			)
		)
		(property "Value" "R_1k_0402"
			(at 283.21 185.42 0)
			(effects
				(font
					(size 1.27 1.27)
					(thickness 0.15)
				)
				(justify left bottom)
				(hide yes)
			)
		)
		(property "Footprint" "antmicro-footprints:R_0402_1005Metric"
			(at 283.21 187.96 0)
			(effects
				(font
					(size 1.27 1.27)
					(thickness 0.15)
				)
				(justify left bottom)
				(hide yes)
			)
		)
		(property "Datasheet" "https://www.bourns.com/docs/product-datasheets/cr.pdf"
			(at 283.21 190.5 0)
			(effects
				(font
					(size 1.27 1.27)
					(thickness 0.15)
				)
				(justify left bottom)
				(hide yes)
			)
		)
		(property "Description" ""
			(at 262.89 172.72 0)
			(effects
				(font
					(size 1.27 1.27)
				)
				(hide yes)
			)
		)
		(property "Manufacturer" "Bourns"
			(at 283.21 195.58 0)
			(effects
				(font
					(size 1.27 1.27)
					(thickness 0.15)
				)
				(justify left bottom)
				(hide yes)
			)
		)
		(property "MPN" "CR0402-FX-1001GLF"
			(at 283.21 193.04 0)
			(effects
				(font
					(size 1.27 1.27)
					(thickness 0.15)
				)
				(justify left bottom)
				(hide yes)
			)
		)
		(property "Val" "1k"
			(at 260.35 172.085 0)
			(effects
				(font
					(size 1.27 1.27)
					(thickness 0.15)
				)
				(justify left bottom)
			)
		)
		(property "License" "Apache-2.0"
			(at 283.21 198.12 0)
			(effects
				(font
					(size 1.27 1.27)
					(thickness 0.15)
				)
				(justify left bottom)
				(hide yes)
			)
		)
		(property "Author" "Antmicro"
			(at 283.21 200.66 0)
			(effects
				(font
					(size 1.27 1.27)
					(thickness 0.15)
				)
				(justify left bottom)
				(hide yes)
			)
		)
		(property "Tolerance" "1%"
			(at 283.21 182.88 0)
			(effects
				(font
					(size 1.27 1.27)
				)
				(justify left bottom)
				(hide yes)
			)
		)
		(pin "1"
		)
		(pin "2"
		)
		(instances
			(project "jetson-orin-baseboard"
				(path ""
					(reference "R98")
					(unit 1)
				)
			)
		)
	)
	(symbol
		(lib_name "C_100n_0402_1")
		(lib_id "antmicroCapacitors0402:C_100n_0402")
		(at 21.59 40.64 270)
		(unit 1)
		(exclude_from_sim no)
		(in_bom yes)
		(on_board yes)
		(dnp no)
		(property "Reference" "C26"
			(at 22.225 41.275 90)
			(effects
				(font
					(size 1.27 1.27)
				)
				(justify left)
			)
		)
		(property "Value" "C_100n_0402"
			(at 11.43 60.96 0)
			(effects
				(font
					(size 1.27 1.27)
					(thickness 0.15)
				)
				(justify left bottom)
				(hide yes)
			)
		)
		(property "Footprint" "antmicro-footprints:C_0402_1005Metric"
			(at 8.89 60.96 0)
			(effects
				(font
					(size 1.27 1.27)
					(thickness 0.15)
				)
				(justify left bottom)
				(hide yes)
			)
		)
		(property "Datasheet" "https://www.murata.com/products/productdetail?partno=GRM155R61H104KE14%23"
			(at 6.35 60.96 0)
			(effects
				(font
					(size 1.27 1.27)
					(thickness 0.15)
				)
				(justify left bottom)
				(hide yes)
			)
		)
		(property "Description" ""
			(at 21.59 40.64 0)
			(effects
				(font
					(size 1.27 1.27)
				)
				(hide yes)
			)
		)
		(property "Manufacturer" "Murata"
			(at 1.27 60.96 0)
			(effects
				(font
					(size 1.27 1.27)
					(thickness 0.15)
				)
				(justify left bottom)
				(hide yes)
			)
		)
		(property "MPN" "GRM155R61H104KE14D"
			(at 3.81 60.96 0)
			(effects
				(font
					(size 1.27 1.27)
					(thickness 0.15)
				)
				(justify left bottom)
				(hide yes)
			)
		)
		(property "Val" "100n"
			(at 22.225 45.085 90)
			(effects
				(font
					(size 1.27 1.27)
					(thickness 0.15)
				)
				(justify left)
			)
		)
		(property "License" "Apache-2.0"
			(at -1.27 60.96 0)
			(effects
				(font
					(size 1.27 1.27)
					(thickness 0.15)
				)
				(justify left bottom)
				(hide yes)
			)
		)
		(property "Author" "Antmicro"
			(at -3.81 60.96 0)
			(effects
				(font
					(size 1.27 1.27)
					(thickness 0.15)
				)
				(justify left bottom)
				(hide yes)
			)
		)
		(property "Voltage" "50V"
			(at -6.35 60.96 0)
			(effects
				(font
					(size 1.27 1.27)
				)
				(justify left bottom)
				(hide yes)
			)
		)
		(property "Dielectric" "X5R"
			(at -8.89 60.96 0)
			(effects
				(font
					(size 1.27 1.27)
				)
				(justify left bottom)
				(hide yes)
			)
		)
		(pin "1"
		)
		(pin "2"
		)
		(instances
			(project "jetson-orin-baseboard"
				(path ""
					(reference "C26")
					(unit 1)
				)
			)
		)
	)
	(symbol
		(lib_name "R_0R_0402_7")
		(lib_id "antmicroResistors0402:R_0R_0402")
		(at 78.74 201.93 0)
		(mirror y)
		(unit 1)
		(exclude_from_sim no)
		(in_bom yes)
		(on_board yes)
		(dnp no)
		(property "Reference" "R56"
			(at 78.74 201.295 0)
			(effects
				(font
					(size 1.27 1.27)
				)
				(justify right bottom)
			)
		)
		(property "Value" "R_0R_0402"
			(at 58.42 214.63 0)
			(effects
				(font
					(size 1.27 1.27)
					(thickness 0.15)
				)
				(justify left bottom)
				(hide yes)
			)
		)
		(property "Footprint" "antmicro-footprints:R_0402_1005Metric"
			(at 58.42 217.17 0)
			(effects
				(font
					(size 1.27 1.27)
					(thickness 0.15)
				)
				(justify left bottom)
				(hide yes)
			)
		)
		(property "Datasheet" "https://industrial.panasonic.com/cdbs/www-data/pdf/RDA0000/AOA0000C301.pdf"
			(at 58.42 219.71 0)
			(effects
				(font
					(size 1.27 1.27)
					(thickness 0.15)
				)
				(justify left bottom)
				(hide yes)
			)
		)
		(property "Description" ""
			(at 78.74 201.93 0)
			(effects
				(font
					(size 1.27 1.27)
				)
				(hide yes)
			)
		)
		(property "Manufacturer" "Panasonic"
			(at 58.42 224.79 0)
			(effects
				(font
					(size 1.27 1.27)
					(thickness 0.15)
				)
				(justify left bottom)
				(hide yes)
			)
		)
		(property "MPN" "ERJ2GE0R00X"
			(at 58.42 222.25 0)
			(effects
				(font
					(size 1.27 1.27)
					(thickness 0.15)
				)
				(justify left bottom)
				(hide yes)
			)
		)
		(property "Val" "0R"
			(at 71.12 201.295 0)
			(effects
				(font
					(size 1.27 1.27)
					(thickness 0.15)
				)
				(justify right bottom)
			)
		)
		(property "License" "Apache-2.0"
			(at 58.42 227.33 0)
			(effects
				(font
					(size 1.27 1.27)
					(thickness 0.15)
				)
				(justify left bottom)
				(hide yes)
			)
		)
		(property "Author" "Antmicro"
			(at 58.42 229.87 0)
			(effects
				(font
					(size 1.27 1.27)
					(thickness 0.15)
				)
				(justify left bottom)
				(hide yes)
			)
		)
		(property "Tolerance" "~"
			(at 58.42 212.09 0)
			(effects
				(font
					(size 1.27 1.27)
				)
				(justify left bottom)
				(hide yes)
			)
		)
		(property "Current" "1A"
			(at 58.42 232.41 0)
			(effects
				(font
					(size 1.27 1.27)
					(thickness 0.15)
				)
				(justify left bottom)
				(hide yes)
			)
		)
		(pin "1"
		)
		(pin "2"
		)
		(instances
			(project "jetson-orin-baseboard"
				(path ""
					(reference "R56")
					(unit 1)
				)
			)
		)
	)
	(symbol
		(lib_id "antmicropower:+3V3")
		(at 170.18 135.89 0)
		(unit 1)
		(exclude_from_sim no)
		(in_bom yes)
		(on_board yes)
		(dnp no)
		(property "Reference" "#PWR09"
			(at 170.18 139.7 0)
			(effects
				(font
					(size 1.27 1.27)
				)
				(justify left bottom)
				(hide yes)
			)
		)
		(property "Value" "+3V3"
			(at 167.005 132.715 0)
			(effects
				(font
					(size 1.27 1.27)
					(thickness 0.15)
				)
				(justify left bottom)
			)
		)
		(property "Footprint" ""
			(at 185.42 143.51 0)
			(effects
				(font
					(size 1.27 1.27)
					(thickness 0.15)
				)
				(justify left bottom)
				(hide yes)
			)
		)
		(property "Datasheet" ""
			(at 185.42 146.05 0)
			(effects
				(font
					(size 1.27 1.27)
					(thickness 0.15)
				)
				(justify left bottom)
				(hide yes)
			)
		)
		(property "Description" ""
			(at 170.18 135.89 0)
			(effects
				(font
					(size 1.27 1.27)
				)
				(hide yes)
			)
		)
		(property "Author" "Antmicro"
			(at 185.42 138.43 0)
			(effects
				(font
					(size 1.27 1.27)
					(thickness 0.15)
				)
				(justify left bottom)
				(hide yes)
			)
		)
		(property "License" "Apache-2.0"
			(at 185.42 140.97 0)
			(effects
				(font
					(size 1.27 1.27)
					(thickness 0.15)
				)
				(justify left bottom)
				(hide yes)
			)
		)
		(pin "1"
		)
		(instances
			(project "jetson-orin-baseboard"
				(path ""
					(reference "#PWR09")
					(unit 1)
				)
			)
		)
	)
	(symbol
		(lib_id "antmicropower:+5V")
		(at 273.05 82.55 0)
		(unit 1)
		(exclude_from_sim no)
		(in_bom yes)
		(on_board yes)
		(dnp no)
		(property "Reference" "#PWR085"
			(at 273.05 86.36 0)
			(effects
				(font
					(size 1.27 1.27)
				)
				(justify left bottom)
				(hide yes)
			)
		)
		(property "Value" "+5V"
			(at 271.145 79.375 0)
			(effects
				(font
					(size 1.27 1.27)
					(thickness 0.15)
				)
				(justify left bottom)
			)
		)
		(property "Footprint" ""
			(at 288.29 90.17 0)
			(effects
				(font
					(size 1.27 1.27)
					(thickness 0.15)
				)
				(justify left bottom)
				(hide yes)
			)
		)
		(property "Datasheet" ""
			(at 288.29 92.71 0)
			(effects
				(font
					(size 1.27 1.27)
					(thickness 0.15)
				)
				(justify left bottom)
				(hide yes)
			)
		)
		(property "Description" ""
			(at 273.05 82.55 0)
			(effects
				(font
					(size 1.27 1.27)
				)
				(hide yes)
			)
		)
		(property "Author" "Antmicro"
			(at 288.29 90.17 0)
			(effects
				(font
					(size 1.27 1.27)
					(thickness 0.15)
				)
				(justify left bottom)
				(hide yes)
			)
		)
		(property "License" "Apache-2.0"
			(at 288.29 92.71 0)
			(effects
				(font
					(size 1.27 1.27)
					(thickness 0.15)
				)
				(justify left bottom)
				(hide yes)
			)
		)
		(pin "1"
		)
		(instances
			(project "jetson-orin-baseboard"
				(path ""
					(reference "#PWR085")
					(unit 1)
				)
			)
		)
	)
	(symbol
		(lib_name "R_0R_0402_10")
		(lib_id "antmicroResistors0402:R_0R_0402")
		(at 198.12 212.09 0)
		(unit 1)
		(exclude_from_sim no)
		(in_bom yes)
		(on_board yes)
		(dnp no)
		(property "Reference" "R76"
			(at 203.2 211.455 0)
			(effects
				(font
					(size 1.27 1.27)
				)
				(justify left bottom)
			)
		)
		(property "Value" "R_0R_0402"
			(at 218.44 224.79 0)
			(effects
				(font
					(size 1.27 1.27)
					(thickness 0.15)
				)
				(justify left bottom)
				(hide yes)
			)
		)
		(property "Footprint" "antmicro-footprints:R_0402_1005Metric"
			(at 218.44 227.33 0)
			(effects
				(font
					(size 1.27 1.27)
					(thickness 0.15)
				)
				(justify left bottom)
				(hide yes)
			)
		)
		(property "Datasheet" "https://industrial.panasonic.com/cdbs/www-data/pdf/RDA0000/AOA0000C301.pdf"
			(at 218.44 229.87 0)
			(effects
				(font
					(size 1.27 1.27)
					(thickness 0.15)
				)
				(justify left bottom)
				(hide yes)
			)
		)
		(property "Description" ""
			(at 198.12 212.09 0)
			(effects
				(font
					(size 1.27 1.27)
				)
				(hide yes)
			)
		)
		(property "Manufacturer" "Panasonic"
			(at 218.44 234.95 0)
			(effects
				(font
					(size 1.27 1.27)
					(thickness 0.15)
				)
				(justify left bottom)
				(hide yes)
			)
		)
		(property "MPN" "ERJ2GE0R00X"
			(at 218.44 232.41 0)
			(effects
				(font
					(size 1.27 1.27)
					(thickness 0.15)
				)
				(justify left bottom)
				(hide yes)
			)
		)
		(property "Val" "0R"
			(at 195.58 211.455 0)
			(effects
				(font
					(size 1.27 1.27)
					(thickness 0.15)
				)
				(justify left bottom)
			)
		)
		(property "License" "Apache-2.0"
			(at 218.44 237.49 0)
			(effects
				(font
					(size 1.27 1.27)
					(thickness 0.15)
				)
				(justify left bottom)
				(hide yes)
			)
		)
		(property "Author" "Antmicro"
			(at 218.44 240.03 0)
			(effects
				(font
					(size 1.27 1.27)
					(thickness 0.15)
				)
				(justify left bottom)
				(hide yes)
			)
		)
		(property "Tolerance" "~"
			(at 218.44 222.25 0)
			(effects
				(font
					(size 1.27 1.27)
				)
				(justify left bottom)
				(hide yes)
			)
		)
		(property "Current" "1A"
			(at 218.44 242.57 0)
			(effects
				(font
					(size 1.27 1.27)
					(thickness 0.15)
				)
				(justify left bottom)
				(hide yes)
			)
		)
		(pin "1"
		)
		(pin "2"
		)
		(instances
			(project "jetson-orin-baseboard"
				(path ""
					(reference "R76")
					(unit 1)
				)
			)
		)
	)
	(symbol
		(lib_id "antmicroResistors0402:R_1k_0402")
		(at 90.17 241.3 270)
		(mirror x)
		(unit 1)
		(exclude_from_sim no)
		(in_bom yes)
		(on_board yes)
		(dnp no)
		(property "Reference" "R267"
			(at 87.63 237.49 90)
			(effects
				(font
					(size 1.27 1.27)
					(thickness 0.15)
				)
				(justify right)
			)
		)
		(property "Value" "R_1k_0402"
			(at 77.47 220.98 0)
			(effects
				(font
					(size 1.27 1.27)
					(thickness 0.15)
				)
				(justify left bottom)
				(hide yes)
			)
		)
		(property "Footprint" "antmicro-footprints:R_0402_1005Metric"
			(at 74.93 220.98 0)
			(effects
				(font
					(size 1.27 1.27)
					(thickness 0.15)
				)
				(justify left bottom)
				(hide yes)
			)
		)
		(property "Datasheet" "https://www.bourns.com/docs/product-datasheets/cr.pdf"
			(at 72.39 220.98 0)
			(effects
				(font
					(size 1.27 1.27)
					(thickness 0.15)
				)
				(justify left bottom)
				(hide yes)
			)
		)
		(property "Description" ""
			(at 90.17 241.3 0)
			(effects
				(font
					(size 1.27 1.27)
				)
				(hide yes)
			)
		)
		(property "MPN" "CR0402-FX-1001GLF"
			(at 69.85 220.98 0)
			(effects
				(font
					(size 1.27 1.27)
					(thickness 0.15)
				)
				(justify left bottom)
				(hide yes)
			)
		)
		(property "Manufacturer" "Bourns"
			(at 67.31 220.98 0)
			(effects
				(font
					(size 1.27 1.27)
					(thickness 0.15)
				)
				(justify left bottom)
				(hide yes)
			)
		)
		(property "License" "Apache-2.0"
			(at 64.77 220.98 0)
			(effects
				(font
					(size 1.27 1.27)
					(thickness 0.15)
				)
				(justify left bottom)
				(hide yes)
			)
		)
		(property "Author" "Antmicro"
			(at 62.23 220.98 0)
			(effects
				(font
					(size 1.27 1.27)
					(thickness 0.15)
				)
				(justify left bottom)
				(hide yes)
			)
		)
		(property "Val" "1k"
			(at 87.63 240.03 90)
			(effects
				(font
					(size 1.27 1.27)
					(thickness 0.15)
				)
				(justify right)
			)
		)
		(property "Tolerance" "1%"
			(at 80.01 220.98 0)
			(effects
				(font
					(size 1.27 1.27)
				)
				(justify left bottom)
				(hide yes)
			)
		)
		(pin "2"
		)
		(pin "1"
		)
		(instances
			(project "jetson-orin-baseboard"
				(path ""
					(reference "R267")
					(unit 1)
				)
			)
		)
	)
	(symbol
		(lib_name "C_100n_0402_2")
		(lib_id "antmicroCapacitors0402:C_100n_0402")
		(at 76.2 130.81 90)
		(unit 1)
		(exclude_from_sim no)
		(in_bom yes)
		(on_board yes)
		(dnp no)
		(fields_autoplaced yes)
		(property "Reference" "C33"
			(at 78.74 126.9936 90)
			(effects
				(font
					(size 1.27 1.27)
				)
				(justify right)
			)
		)
		(property "Value" "C_100n_0402"
			(at 86.36 110.49 0)
			(effects
				(font
					(size 1.27 1.27)
					(thickness 0.15)
				)
				(justify left bottom)
				(hide yes)
			)
		)
		(property "Footprint" "antmicro-footprints:C_0402_1005Metric"
			(at 88.9 110.49 0)
			(effects
				(font
					(size 1.27 1.27)
					(thickness 0.15)
				)
				(justify left bottom)
				(hide yes)
			)
		)
		(property "Datasheet" "https://www.murata.com/products/productdetail?partno=GRM155R61H104KE14%23"
			(at 91.44 110.49 0)
			(effects
				(font
					(size 1.27 1.27)
					(thickness 0.15)
				)
				(justify left bottom)
				(hide yes)
			)
		)
		(property "Description" ""
			(at 76.2 130.81 0)
			(effects
				(font
					(size 1.27 1.27)
				)
				(hide yes)
			)
		)
		(property "Manufacturer" "Murata"
			(at 96.52 110.49 0)
			(effects
				(font
					(size 1.27 1.27)
					(thickness 0.15)
				)
				(justify left bottom)
				(hide yes)
			)
		)
		(property "MPN" "GRM155R61H104KE14D"
			(at 93.98 110.49 0)
			(effects
				(font
					(size 1.27 1.27)
					(thickness 0.15)
				)
				(justify left bottom)
				(hide yes)
			)
		)
		(property "Val" "100n"
			(at 78.74 129.5336 90)
			(effects
				(font
					(size 1.27 1.27)
					(thickness 0.15)
				)
				(justify right)
			)
		)
		(property "License" "Apache-2.0"
			(at 99.06 110.49 0)
			(effects
				(font
					(size 1.27 1.27)
					(thickness 0.15)
				)
				(justify left bottom)
				(hide yes)
			)
		)
		(property "Author" "Antmicro"
			(at 101.6 110.49 0)
			(effects
				(font
					(size 1.27 1.27)
					(thickness 0.15)
				)
				(justify left bottom)
				(hide yes)
			)
		)
		(property "Voltage" "50V"
			(at 104.14 110.49 0)
			(effects
				(font
					(size 1.27 1.27)
				)
				(justify left bottom)
				(hide yes)
			)
		)
		(property "Dielectric" "X5R"
			(at 106.68 110.49 0)
			(effects
				(font
					(size 1.27 1.27)
				)
				(justify left bottom)
				(hide yes)
			)
		)
		(pin "1"
		)
		(pin "2"
		)
		(instances
			(project "jetson-orin-baseboard"
				(path ""
					(reference "C33")
					(unit 1)
				)
			)
		)
	)
	(symbol
		(lib_name "GND_3")
		(lib_id "antmicropower:GND")
		(at 193.04 250.19 0)
		(mirror y)
		(unit 1)
		(exclude_from_sim no)
		(in_bom yes)
		(on_board yes)
		(dnp no)
		(property "Reference" "#PWR074"
			(at 193.04 256.54 0)
			(effects
				(font
					(size 1.27 1.27)
				)
				(justify left bottom)
				(hide yes)
			)
		)
		(property "Value" "GND"
			(at 193.04 254 0)
			(effects
				(font
					(size 1.27 1.27)
					(thickness 0.15)
				)
			)
		)
		(property "Footprint" ""
			(at 184.15 257.81 0)
			(effects
				(font
					(size 1.27 1.27)
					(thickness 0.15)
				)
				(justify left bottom)
				(hide yes)
			)
		)
		(property "Datasheet" ""
			(at 184.15 262.89 0)
			(effects
				(font
					(size 1.27 1.27)
					(thickness 0.15)
				)
				(justify left bottom)
				(hide yes)
			)
		)
		(property "Description" ""
			(at 193.04 250.19 0)
			(effects
				(font
					(size 1.27 1.27)
				)
				(hide yes)
			)
		)
		(property "Author" "Antmicro"
			(at 184.15 257.81 0)
			(effects
				(font
					(size 1.27 1.27)
					(thickness 0.15)
				)
				(justify left bottom)
				(hide yes)
			)
		)
		(property "License" "Apache-2.0"
			(at 184.15 260.35 0)
			(effects
				(font
					(size 1.27 1.27)
					(thickness 0.15)
				)
				(justify left bottom)
				(hide yes)
			)
		)
		(pin "1"
		)
		(instances
			(project "jetson-orin-baseboard"
				(path ""
					(reference "#PWR074")
					(unit 1)
				)
			)
		)
	)
	(symbol
		(lib_name "C_4u7_25V_0402_1")
		(lib_id "antmicroCapacitors0402:C_4u7_25V_0402")
		(at 193.04 243.84 270)
		(unit 1)
		(exclude_from_sim no)
		(in_bom yes)
		(on_board yes)
		(dnp no)
		(fields_autoplaced yes)
		(property "Reference" "C136"
			(at 195.58 245.1163 90)
			(effects
				(font
					(size 1.27 1.27)
				)
				(justify left)
			)
		)
		(property "Value" "C_4u7_25V_0402"
			(at 182.88 264.16 0)
			(effects
				(font
					(size 1.27 1.27)
					(thickness 0.15)
				)
				(justify left bottom)
				(hide yes)
			)
		)
		(property "Footprint" "antmicro-footprints:C_0402_1005Metric"
			(at 180.34 264.16 0)
			(effects
				(font
					(size 1.27 1.27)
					(thickness 0.15)
				)
				(justify left bottom)
				(hide yes)
			)
		)
		(property "Datasheet" "https://www.murata.com/products/productdetail?partno=GRM155C61E475ME15%23"
			(at 177.8 264.16 0)
			(effects
				(font
					(size 1.27 1.27)
					(thickness 0.15)
				)
				(justify left bottom)
				(hide yes)
			)
		)
		(property "Description" ""
			(at 193.04 243.84 0)
			(effects
				(font
					(size 1.27 1.27)
				)
				(hide yes)
			)
		)
		(property "Manufacturer" "Murata"
			(at 172.72 264.16 0)
			(effects
				(font
					(size 1.27 1.27)
					(thickness 0.15)
				)
				(justify left bottom)
				(hide yes)
			)
		)
		(property "MPN" "GRM155C61E475ME15J"
			(at 175.26 264.16 0)
			(effects
				(font
					(size 1.27 1.27)
					(thickness 0.15)
				)
				(justify left bottom)
				(hide yes)
			)
		)
		(property "Val" "4u7"
			(at 195.58 247.6563 90)
			(effects
				(font
					(size 1.27 1.27)
					(thickness 0.15)
				)
				(justify left)
			)
		)
		(property "License" "Apache-2.0"
			(at 170.18 264.16 0)
			(effects
				(font
					(size 1.27 1.27)
					(thickness 0.15)
				)
				(justify left bottom)
				(hide yes)
			)
		)
		(property "Author" "Antmicro"
			(at 167.64 264.16 0)
			(effects
				(font
					(size 1.27 1.27)
					(thickness 0.15)
				)
				(justify left bottom)
				(hide yes)
			)
		)
		(property "Voltage" "25V"
			(at 165.1 264.16 0)
			(effects
				(font
					(size 1.27 1.27)
				)
				(justify left bottom)
				(hide yes)
			)
		)
		(property "Dielectric" "X5S"
			(at 162.56 264.16 0)
			(effects
				(font
					(size 1.27 1.27)
				)
				(justify left bottom)
				(hide yes)
			)
		)
		(pin "1"
		)
		(pin "2"
		)
		(instances
			(project "jetson-orin-baseboard"
				(path ""
					(reference "C136")
					(unit 1)
				)
			)
		)
	)
	(symbol
		(lib_id "antmicroTVSDiodes:DF2S30FS_SOD")
		(at 360.68 41.91 270)
		(unit 1)
		(exclude_from_sim no)
		(in_bom yes)
		(on_board yes)
		(dnp no)
		(property "Reference" "D7"
			(at 362.585 43.18 90)
			(effects
				(font
					(size 1.27 1.27)
				)
				(justify left)
			)
		)
		(property "Value" "DF2S30FS_SOD"
			(at 345.44 63.5 0)
			(effects
				(font
					(size 1.27 1.27)
					(thickness 0.15)
				)
				(justify left bottom)
				(hide yes)
			)
		)
		(property "Footprint" "antmicro-footprints:SOD-923"
			(at 353.06 63.5 0)
			(effects
				(font
					(size 1.27 1.27)
					(thickness 0.15)
				)
				(justify left bottom)
				(hide yes)
			)
		)
		(property "Datasheet" "https://toshiba.semicon-storage.com/info/DF2S30FS_datasheet_en_20211216.pdf?did=11156&prodName=DF2S30FS"
			(at 350.52 63.5 0)
			(effects
				(font
					(size 1.27 1.27)
					(thickness 0.15)
				)
				(justify left bottom)
				(hide yes)
			)
		)
		(property "Description" ""
			(at 360.68 41.91 0)
			(effects
				(font
					(size 1.27 1.27)
				)
				(hide yes)
			)
		)
		(property "Manufacturer" "Toshiba"
			(at 347.98 63.5 0)
			(effects
				(font
					(size 1.27 1.27)
					(thickness 0.15)
				)
				(justify left bottom)
				(hide yes)
			)
		)
		(property "MPN" "DF2S30FS"
			(at 362.585 45.72 90)
			(effects
				(font
					(size 1.27 1.27)
					(thickness 0.15)
				)
				(justify left)
			)
		)
		(property "Author" "Antmicro"
			(at 342.9 63.5 0)
			(effects
				(font
					(size 1.27 1.27)
					(thickness 0.15)
				)
				(justify left bottom)
				(hide yes)
			)
		)
		(property "License" "Apache-2.0"
			(at 340.36 63.5 0)
			(effects
				(font
					(size 1.27 1.27)
					(thickness 0.15)
				)
				(justify left bottom)
				(hide yes)
			)
		)
		(pin "1"
		)
		(pin "2"
		)
		(instances
			(project "jetson-orin-baseboard"
				(path ""
					(reference "D7")
					(unit 1)
				)
			)
		)
	)
	(symbol
		(lib_id "antmicroTestPoints:TP_0.75mm_SMD")
		(at 207.01 170.18 180)
		(unit 1)
		(exclude_from_sim no)
		(in_bom no)
		(on_board yes)
		(dnp no)
		(property "Reference" "TP28"
			(at 200.66 170.18 0)
			(effects
				(font
					(size 1.27 1.27)
				)
			)
		)
		(property "Value" "TP_0.75mm_SMD"
			(at 196.85 166.37 0)
			(effects
				(font
					(size 1.27 1.27)
					(thickness 0.15)
				)
				(justify left bottom)
				(hide yes)
			)
		)
		(property "Footprint" "antmicro-footprints:TP_SMD_0.75mm"
			(at 196.85 163.83 0)
			(effects
				(font
					(size 1.27 1.27)
					(thickness 0.15)
				)
				(justify left bottom)
				(hide yes)
			)
		)
		(property "Datasheet" ""
			(at 189.23 157.48 0)
			(effects
				(font
					(size 1.27 1.27)
					(thickness 0.15)
				)
				(justify left bottom)
				(hide yes)
			)
		)
		(property "Description" ""
			(at 207.01 170.18 0)
			(effects
				(font
					(size 1.27 1.27)
				)
				(hide yes)
			)
		)
		(property "MPN" ""
			(at 196.215 158.75 0)
			(effects
				(font
					(size 1.27 1.27)
					(thickness 0.15)
				)
				(justify left bottom)
				(hide yes)
			)
		)
		(property "Manufacturer" ""
			(at 196.215 163.83 0)
			(effects
				(font
					(size 1.27 1.27)
					(thickness 0.15)
				)
				(justify left bottom)
				(hide yes)
			)
		)
		(property "Author" "Antmicro"
			(at 196.85 161.29 0)
			(effects
				(font
					(size 1.27 1.27)
					(thickness 0.15)
				)
				(justify left bottom)
				(hide yes)
			)
		)
		(property "License" "Apache-2.0"
			(at 196.85 158.75 0)
			(effects
				(font
					(size 1.27 1.27)
					(thickness 0.15)
				)
				(justify left bottom)
				(hide yes)
			)
		)
		(pin "1"
		)
		(instances
			(project "jetson-orin-baseboard"
				(path ""
					(reference "TP28")
					(unit 1)
				)
			)
		)
	)
	(symbol
		(lib_name "GND_3")
		(lib_id "antmicropower:GND")
		(at 187.96 250.19 0)
		(mirror y)
		(unit 1)
		(exclude_from_sim no)
		(in_bom yes)
		(on_board yes)
		(dnp no)
		(property "Reference" "#PWR068"
			(at 187.96 256.54 0)
			(effects
				(font
					(size 1.27 1.27)
				)
				(justify left bottom)
				(hide yes)
			)
		)
		(property "Value" "GND"
			(at 187.96 254 0)
			(effects
				(font
					(size 1.27 1.27)
					(thickness 0.15)
				)
			)
		)
		(property "Footprint" ""
			(at 179.07 257.81 0)
			(effects
				(font
					(size 1.27 1.27)
					(thickness 0.15)
				)
				(justify left bottom)
				(hide yes)
			)
		)
		(property "Datasheet" ""
			(at 179.07 262.89 0)
			(effects
				(font
					(size 1.27 1.27)
					(thickness 0.15)
				)
				(justify left bottom)
				(hide yes)
			)
		)
		(property "Description" ""
			(at 187.96 250.19 0)
			(effects
				(font
					(size 1.27 1.27)
				)
				(hide yes)
			)
		)
		(property "Author" "Antmicro"
			(at 179.07 257.81 0)
			(effects
				(font
					(size 1.27 1.27)
					(thickness 0.15)
				)
				(justify left bottom)
				(hide yes)
			)
		)
		(property "License" "Apache-2.0"
			(at 179.07 260.35 0)
			(effects
				(font
					(size 1.27 1.27)
					(thickness 0.15)
				)
				(justify left bottom)
				(hide yes)
			)
		)
		(pin "1"
		)
		(instances
			(project "jetson-orin-baseboard"
				(path ""
					(reference "#PWR068")
					(unit 1)
				)
			)
		)
	)
	(symbol
		(lib_name "+5V_1")
		(lib_id "antmicropower:+5V")
		(at 193.04 259.08 0)
		(unit 1)
		(exclude_from_sim no)
		(in_bom yes)
		(on_board yes)
		(dnp no)
		(property "Reference" "#PWR067"
			(at 193.04 262.89 0)
			(effects
				(font
					(size 1.27 1.27)
				)
				(justify left bottom)
				(hide yes)
			)
		)
		(property "Value" "+5V"
			(at 208.28 264.16 0)
			(effects
				(font
					(size 1.27 1.27)
					(thickness 0.15)
				)
				(justify left bottom)
			)
		)
		(property "Footprint" ""
			(at 208.28 266.7 0)
			(effects
				(font
					(size 1.27 1.27)
					(thickness 0.15)
				)
				(justify left bottom)
				(hide yes)
			)
		)
		(property "Datasheet" ""
			(at 208.28 269.24 0)
			(effects
				(font
					(size 1.27 1.27)
					(thickness 0.15)
				)
				(justify left bottom)
				(hide yes)
			)
		)
		(property "Description" ""
			(at 193.04 259.08 0)
			(effects
				(font
					(size 1.27 1.27)
				)
				(hide yes)
			)
		)
		(property "Author" "Antmicro"
			(at 208.28 266.7 0)
			(effects
				(font
					(size 1.27 1.27)
					(thickness 0.15)
				)
				(justify left bottom)
				(hide yes)
			)
		)
		(property "License" "Apache-2.0"
			(at 208.28 269.24 0)
			(effects
				(font
					(size 1.27 1.27)
					(thickness 0.15)
				)
				(justify left bottom)
				(hide yes)
			)
		)
		(pin "1"
		)
		(instances
			(project "jetson-orin-baseboard"
				(path ""
					(reference "#PWR067")
					(unit 1)
				)
			)
		)
	)
	(symbol
		(lib_name "GND_3")
		(lib_id "antmicropower:GND")
		(at 283.21 137.16 0)
		(mirror y)
		(unit 1)
		(exclude_from_sim no)
		(in_bom yes)
		(on_board yes)
		(dnp no)
		(property "Reference" "#PWR093"
			(at 283.21 143.51 0)
			(effects
				(font
					(size 1.27 1.27)
				)
				(justify left bottom)
				(hide yes)
			)
		)
		(property "Value" "GND"
			(at 283.21 140.97 0)
			(effects
				(font
					(size 1.27 1.27)
					(thickness 0.15)
				)
			)
		)
		(property "Footprint" ""
			(at 274.32 144.78 0)
			(effects
				(font
					(size 1.27 1.27)
					(thickness 0.15)
				)
				(justify left bottom)
				(hide yes)
			)
		)
		(property "Datasheet" ""
			(at 274.32 149.86 0)
			(effects
				(font
					(size 1.27 1.27)
					(thickness 0.15)
				)
				(justify left bottom)
				(hide yes)
			)
		)
		(property "Description" ""
			(at 283.21 137.16 0)
			(effects
				(font
					(size 1.27 1.27)
				)
				(hide yes)
			)
		)
		(property "Author" "Antmicro"
			(at 274.32 144.78 0)
			(effects
				(font
					(size 1.27 1.27)
					(thickness 0.15)
				)
				(justify left bottom)
				(hide yes)
			)
		)
		(property "License" "Apache-2.0"
			(at 274.32 147.32 0)
			(effects
				(font
					(size 1.27 1.27)
					(thickness 0.15)
				)
				(justify left bottom)
				(hide yes)
			)
		)
		(pin "1"
		)
		(instances
			(project "jetson-orin-baseboard"
				(path ""
					(reference "#PWR093")
					(unit 1)
				)
			)
		)
	)
	(symbol
		(lib_id "antmicroCapacitors0402:C_47p_0402")
		(at 341.63 229.87 90)
		(unit 1)
		(exclude_from_sim no)
		(in_bom yes)
		(on_board yes)
		(dnp no)
		(fields_autoplaced yes)
		(property "Reference" "C145"
			(at 339.09 226.0536 90)
			(effects
				(font
					(size 1.27 1.27)
					(thickness 0.15)
				)
				(justify left)
			)
		)
		(property "Value" "C_47p_0402"
			(at 351.79 209.55 0)
			(effects
				(font
					(size 1.27 1.27)
					(thickness 0.15)
				)
				(justify left bottom)
				(hide yes)
			)
		)
		(property "Footprint" "antmicro-footprints:C_0402_1005Metric"
			(at 354.33 209.55 0)
			(effects
				(font
					(size 1.27 1.27)
					(thickness 0.15)
				)
				(justify left bottom)
				(hide yes)
			)
		)
		(property "Datasheet" "https://www.kemet.com/en/us/capacitors/product/C0402C470J5GACTU.html"
			(at 356.87 209.55 0)
			(effects
				(font
					(size 1.27 1.27)
					(thickness 0.15)
				)
				(justify left bottom)
				(hide yes)
			)
		)
		(property "Description" ""
			(at 341.63 229.87 0)
			(effects
				(font
					(size 1.27 1.27)
				)
				(hide yes)
			)
		)
		(property "MPN" "C0402C470J5GACTU"
			(at 359.41 209.55 0)
			(effects
				(font
					(size 1.27 1.27)
					(thickness 0.15)
				)
				(justify left bottom)
				(hide yes)
			)
		)
		(property "Manufacturer" "KEMET"
			(at 361.95 209.55 0)
			(effects
				(font
					(size 1.27 1.27)
					(thickness 0.15)
				)
				(justify left bottom)
				(hide yes)
			)
		)
		(property "License" "Apache-2.0"
			(at 364.49 209.55 0)
			(effects
				(font
					(size 1.27 1.27)
					(thickness 0.15)
				)
				(justify left bottom)
				(hide yes)
			)
		)
		(property "Author" "Antmicro"
			(at 367.03 209.55 0)
			(effects
				(font
					(size 1.27 1.27)
					(thickness 0.15)
				)
				(justify left bottom)
				(hide yes)
			)
		)
		(property "Val" "47p"
			(at 339.09 228.5936 90)
			(effects
				(font
					(size 1.27 1.27)
					(thickness 0.15)
				)
				(justify left)
			)
		)
		(property "Voltage" ""
			(at 369.57 209.55 0)
			(effects
				(font
					(size 1.27 1.27)
				)
				(justify left bottom)
				(hide yes)
			)
		)
		(property "Dielectric" "C0G"
			(at 372.11 209.55 0)
			(effects
				(font
					(size 1.27 1.27)
				)
				(justify left bottom)
				(hide yes)
			)
		)
		(pin "2"
		)
		(pin "1"
		)
		(instances
			(project "jetson-orin-baseboard"
				(path ""
					(reference "C145")
					(unit 1)
				)
			)
		)
	)
	(symbol
		(lib_id "antmicroCapacitors0402:C_10u_0402")
		(at 15.24 199.39 90)
		(unit 1)
		(exclude_from_sim no)
		(in_bom yes)
		(on_board yes)
		(dnp no)
		(fields_autoplaced yes)
		(property "Reference" "C34"
			(at 17.78 195.5736 90)
			(effects
				(font
					(size 1.27 1.27)
					(thickness 0.15)
				)
				(justify right)
			)
		)
		(property "Value" "C_10u_0402"
			(at 25.4 179.07 0)
			(effects
				(font
					(size 1.27 1.27)
					(thickness 0.15)
				)
				(justify left bottom)
				(hide yes)
			)
		)
		(property "Footprint" "antmicro-footprints:C_0402_1005Metric"
			(at 27.94 179.07 0)
			(effects
				(font
					(size 1.27 1.27)
					(thickness 0.15)
				)
				(justify left bottom)
				(hide yes)
			)
		)
		(property "Datasheet" "https://www.yageo.com/en/Chart/Download/pdf/CC0402MRX5R5BB106"
			(at 30.48 179.07 0)
			(effects
				(font
					(size 1.27 1.27)
					(thickness 0.15)
				)
				(justify left bottom)
				(hide yes)
			)
		)
		(property "Description" ""
			(at 15.24 199.39 0)
			(effects
				(font
					(size 1.27 1.27)
				)
				(hide yes)
			)
		)
		(property "MPN" "CC0402MRX5R5BB106"
			(at 33.02 179.07 0)
			(effects
				(font
					(size 1.27 1.27)
					(thickness 0.15)
				)
				(justify left bottom)
				(hide yes)
			)
		)
		(property "Manufacturer" "YAGEO"
			(at 35.56 179.07 0)
			(effects
				(font
					(size 1.27 1.27)
					(thickness 0.15)
				)
				(justify left bottom)
				(hide yes)
			)
		)
		(property "License" "Apache-2.0"
			(at 38.1 179.07 0)
			(effects
				(font
					(size 1.27 1.27)
					(thickness 0.15)
				)
				(justify left bottom)
				(hide yes)
			)
		)
		(property "Author" "Antmicro"
			(at 40.64 179.07 0)
			(effects
				(font
					(size 1.27 1.27)
					(thickness 0.15)
				)
				(justify left bottom)
				(hide yes)
			)
		)
		(property "Val" "10u"
			(at 17.78 198.1136 90)
			(effects
				(font
					(size 1.27 1.27)
					(thickness 0.15)
				)
				(justify right)
			)
		)
		(property "Voltage" ""
			(at 43.18 179.07 0)
			(effects
				(font
					(size 1.27 1.27)
				)
				(justify left bottom)
				(hide yes)
			)
		)
		(property "Dielectric" ""
			(at 45.72 179.07 0)
			(effects
				(font
					(size 1.27 1.27)
				)
				(justify left bottom)
				(hide yes)
			)
		)
		(pin "1"
		)
		(pin "2"
		)
		(instances
			(project "jetson-orin-baseboard"
				(path ""
					(reference "C34")
					(unit 1)
				)
			)
		)
	)
	(symbol
		(lib_name "R_4k7_0402_3")
		(lib_id "antmicroResistors0402:R_4k7_0402")
		(at 132.08 125.73 180)
		(unit 1)
		(exclude_from_sim no)
		(in_bom yes)
		(on_board yes)
		(dnp no)
		(property "Reference" "R262"
			(at 132.08 125.095 0)
			(effects
				(font
					(size 1.27 1.27)
				)
				(justify right top)
			)
		)
		(property "Value" "R_4k7_0402"
			(at 111.76 113.03 0)
			(effects
				(font
					(size 1.27 1.27)
					(thickness 0.15)
				)
				(justify left bottom)
				(hide yes)
			)
		)
		(property "Footprint" "antmicro-footprints:R_0402_1005Metric"
			(at 111.76 110.49 0)
			(effects
				(font
					(size 1.27 1.27)
					(thickness 0.15)
				)
				(justify left bottom)
				(hide yes)
			)
		)
		(property "Datasheet" "https://www.bourns.com/docs/product-datasheets/cr.pdf"
			(at 111.76 107.95 0)
			(effects
				(font
					(size 1.27 1.27)
					(thickness 0.15)
				)
				(justify left bottom)
				(hide yes)
			)
		)
		(property "Description" ""
			(at 132.08 125.73 0)
			(effects
				(font
					(size 1.27 1.27)
				)
				(hide yes)
			)
		)
		(property "Manufacturer" "Bourns"
			(at 111.76 102.87 0)
			(effects
				(font
					(size 1.27 1.27)
					(thickness 0.15)
				)
				(justify left bottom)
				(hide yes)
			)
		)
		(property "MPN" "CR0402-FX-4701GLF"
			(at 111.76 105.41 0)
			(effects
				(font
					(size 1.27 1.27)
					(thickness 0.15)
				)
				(justify left bottom)
				(hide yes)
			)
		)
		(property "Val" "4k7"
			(at 123.19 125.095 0)
			(effects
				(font
					(size 1.27 1.27)
					(thickness 0.15)
				)
				(justify right top)
			)
		)
		(property "License" "Apache-2.0"
			(at 111.76 100.33 0)
			(effects
				(font
					(size 1.27 1.27)
					(thickness 0.15)
				)
				(justify left bottom)
				(hide yes)
			)
		)
		(property "Author" "Antmicro"
			(at 111.76 97.79 0)
			(effects
				(font
					(size 1.27 1.27)
					(thickness 0.15)
				)
				(justify left bottom)
				(hide yes)
			)
		)
		(property "Tolerance" "1%"
			(at 111.76 115.57 0)
			(effects
				(font
					(size 1.27 1.27)
				)
				(justify left bottom)
				(hide yes)
			)
		)
		(pin "1"
		)
		(pin "2"
		)
		(instances
			(project "jetson-orin-baseboard"
				(path ""
					(reference "R262")
					(unit 1)
				)
			)
		)
	)
	(symbol
		(lib_name "TPS65988DHRSHR_2")
		(lib_id "antmicroInterfaceControllers:TPS65988DHRSHR")
		(at 234.95 252.73 0)
		(mirror y)
		(unit 2)
		(exclude_from_sim no)
		(in_bom yes)
		(on_board yes)
		(dnp no)
		(property "Reference" "U6"
			(at 219.075 245.11 0)
			(effects
				(font
					(size 1.27 1.27)
				)
			)
		)
		(property "Value" "TPS65988DHRSHR"
			(at 185.42 257.81 0)
			(effects
				(font
					(size 1.27 1.27)
					(thickness 0.15)
				)
				(justify left bottom)
				(hide yes)
			)
		)
		(property "Footprint" "antmicro-footprints:IC_TPS65987DDHRSHR"
			(at 185.42 260.35 0)
			(effects
				(font
					(size 1.27 1.27)
					(thickness 0.15)
				)
				(justify left bottom)
				(hide yes)
			)
		)
		(property "Datasheet" "https://www.ti.com/lit/ds/symlink/tps65988.pdf?ts=1662726631004&ref_url=https%253A%252F%252Fwww.ti.com%252Fproduct%252FTPS65988"
			(at 185.42 262.89 0)
			(effects
				(font
					(size 1.27 1.27)
					(thickness 0.15)
				)
				(justify left bottom)
				(hide yes)
			)
		)
		(property "Description" ""
			(at 234.95 252.73 0)
			(effects
				(font
					(size 1.27 1.27)
				)
				(hide yes)
			)
		)
		(property "MPN" "TPS65988DHRSHR "
			(at 219.075 247.65 0)
			(effects
				(font
					(size 1.27 1.27)
					(thickness 0.15)
				)
			)
		)
		(property "Manufacturer" "Texas Instruments"
			(at 185.42 267.97 0)
			(effects
				(font
					(size 1.27 1.27)
					(thickness 0.15)
				)
				(justify left bottom)
				(hide yes)
			)
		)
		(property "License" "Apache-2.0"
			(at 185.42 270.51 0)
			(effects
				(font
					(size 1.27 1.27)
					(thickness 0.15)
				)
				(justify left bottom)
				(hide yes)
			)
		)
		(property "Author" "Antmicro"
			(at 185.42 273.05 0)
			(effects
				(font
					(size 1.27 1.27)
					(thickness 0.15)
				)
				(justify left bottom)
				(hide yes)
			)
		)
		(pin "10"
		)
		(pin "16"
		)
		(pin "17"
		)
		(pin "18"
		)
		(pin "20"
		)
		(pin "21"
		)
		(pin "22"
		)
		(pin "23"
		)
		(pin "27"
		)
		(pin "28"
		)
		(pin "29"
		)
		(pin "30"
		)
		(pin "31"
		)
		(pin "32"
		)
		(pin "33"
		)
		(pin "34"
		)
		(pin "35"
		)
		(pin "36"
		)
		(pin "37"
		)
		(pin "38"
		)
		(pin "39"
		)
		(pin "40"
		)
		(pin "41"
		)
		(pin "42"
		)
		(pin "43"
		)
		(pin "44"
		)
		(pin "48"
		)
		(pin "49"
		)
		(pin "5"
		)
		(pin "51"
		)
		(pin "59"
		)
		(pin "6"
		)
		(pin "9"
		)
		(pin "11"
		)
		(pin "13"
		)
		(pin "15"
		)
		(pin "19"
		)
		(pin "24"
		)
		(pin "25"
		)
		(pin "26"
		)
		(pin "50"
		)
		(pin "53"
		)
		(pin "58"
		)
		(pin "8"
		)
		(pin "1"
		)
		(pin "3"
		)
		(pin "45"
		)
		(pin "46"
		)
		(pin "47"
		)
		(pin "52"
		)
		(pin "54"
		)
		(pin "55"
		)
		(pin "56"
		)
		(pin "57"
		)
		(pin "7"
		)
		(instances
			(project "jetson-orin-baseboard"
				(path ""
					(reference "U6")
					(unit 2)
				)
			)
		)
	)
	(symbol
		(lib_name "TP_0.75mm_SMD_1")
		(lib_id "antmicroTestPoints:TP_0.75mm_SMD")
		(at 107.95 58.42 0)
		(unit 1)
		(exclude_from_sim no)
		(in_bom no)
		(on_board yes)
		(dnp no)
		(property "Reference" "TP25"
			(at 111.76 59.055 0)
			(effects
				(font
					(size 1.27 1.27)
				)
				(justify left bottom)
			)
		)
		(property "Value" "TP_0.75mm_SMD"
			(at 118.11 62.23 0)
			(effects
				(font
					(size 1.27 1.27)
					(thickness 0.15)
				)
				(justify left bottom)
				(hide yes)
			)
		)
		(property "Footprint" "antmicro-footprints:TP_SMD_0.75mm"
			(at 118.11 64.77 0)
			(effects
				(font
					(size 1.27 1.27)
					(thickness 0.15)
				)
				(justify left bottom)
				(hide yes)
			)
		)
		(property "Datasheet" ""
			(at 125.73 71.12 0)
			(effects
				(font
					(size 1.27 1.27)
					(thickness 0.15)
				)
				(justify left bottom)
				(hide yes)
			)
		)
		(property "Description" ""
			(at 107.95 58.42 0)
			(effects
				(font
					(size 1.27 1.27)
				)
				(hide yes)
			)
		)
		(property "MPN" ""
			(at 118.745 69.85 0)
			(effects
				(font
					(size 1.27 1.27)
					(thickness 0.15)
				)
				(justify left bottom)
				(hide yes)
			)
		)
		(property "Manufacturer" ""
			(at 118.745 64.77 0)
			(effects
				(font
					(size 1.27 1.27)
					(thickness 0.15)
				)
				(justify left bottom)
				(hide yes)
			)
		)
		(property "Author" "Antmicro"
			(at 118.11 67.31 0)
			(effects
				(font
					(size 1.27 1.27)
					(thickness 0.15)
				)
				(justify left bottom)
				(hide yes)
			)
		)
		(property "License" "Apache-2.0"
			(at 118.11 69.85 0)
			(effects
				(font
					(size 1.27 1.27)
					(thickness 0.15)
				)
				(justify left bottom)
				(hide yes)
			)
		)
		(pin "1"
		)
		(instances
			(project "jetson-orin-baseboard"
				(path ""
					(reference "TP25")
					(unit 1)
				)
			)
		)
	)
	(symbol
		(lib_id "antmicroResistors0402:R_1k_0402")
		(at 262.89 162.56 0)
		(unit 1)
		(exclude_from_sim no)
		(in_bom yes)
		(on_board yes)
		(dnp no)
		(property "Reference" "R94"
			(at 268.605 161.925 0)
			(effects
				(font
					(size 1.27 1.27)
				)
				(justify left bottom)
			)
		)
		(property "Value" "R_1k_0402"
			(at 283.21 175.26 0)
			(effects
				(font
					(size 1.27 1.27)
					(thickness 0.15)
				)
				(justify left bottom)
				(hide yes)
			)
		)
		(property "Footprint" "antmicro-footprints:R_0402_1005Metric"
			(at 283.21 177.8 0)
			(effects
				(font
					(size 1.27 1.27)
					(thickness 0.15)
				)
				(justify left bottom)
				(hide yes)
			)
		)
		(property "Datasheet" "https://www.bourns.com/docs/product-datasheets/cr.pdf"
			(at 283.21 180.34 0)
			(effects
				(font
					(size 1.27 1.27)
					(thickness 0.15)
				)
				(justify left bottom)
				(hide yes)
			)
		)
		(property "Description" ""
			(at 262.89 162.56 0)
			(effects
				(font
					(size 1.27 1.27)
				)
				(hide yes)
			)
		)
		(property "Manufacturer" "Bourns"
			(at 283.21 185.42 0)
			(effects
				(font
					(size 1.27 1.27)
					(thickness 0.15)
				)
				(justify left bottom)
				(hide yes)
			)
		)
		(property "MPN" "CR0402-FX-1001GLF"
			(at 283.21 182.88 0)
			(effects
				(font
					(size 1.27 1.27)
					(thickness 0.15)
				)
				(justify left bottom)
				(hide yes)
			)
		)
		(property "Val" "1k"
			(at 260.35 161.925 0)
			(effects
				(font
					(size 1.27 1.27)
					(thickness 0.15)
				)
				(justify left bottom)
			)
		)
		(property "License" "Apache-2.0"
			(at 283.21 187.96 0)
			(effects
				(font
					(size 1.27 1.27)
					(thickness 0.15)
				)
				(justify left bottom)
				(hide yes)
			)
		)
		(property "Author" "Antmicro"
			(at 283.21 190.5 0)
			(effects
				(font
					(size 1.27 1.27)
					(thickness 0.15)
				)
				(justify left bottom)
				(hide yes)
			)
		)
		(property "Tolerance" "1%"
			(at 283.21 172.72 0)
			(effects
				(font
					(size 1.27 1.27)
				)
				(justify left bottom)
				(hide yes)
			)
		)
		(pin "1"
		)
		(pin "2"
		)
		(instances
			(project "jetson-orin-baseboard"
				(path ""
					(reference "R94")
					(unit 1)
				)
			)
		)
	)
	(symbol
		(lib_id "antmicroCapacitors0402:C_100n_0402")
		(at 184.15 124.46 0)
		(mirror x)
		(unit 1)
		(exclude_from_sim no)
		(in_bom yes)
		(on_board yes)
		(dnp no)
		(property "Reference" "C141"
			(at 190.5 123.19 0)
			(effects
				(font
					(size 1.27 1.27)
				)
			)
		)
		(property "Value" "C_100n_0402"
			(at 204.47 114.3 0)
			(effects
				(font
					(size 1.27 1.27)
					(thickness 0.15)
				)
				(justify left bottom)
				(hide yes)
			)
		)
		(property "Footprint" "antmicro-footprints:C_0402_1005Metric"
			(at 204.47 111.76 0)
			(effects
				(font
					(size 1.27 1.27)
					(thickness 0.15)
				)
				(justify left bottom)
				(hide yes)
			)
		)
		(property "Datasheet" "https://www.murata.com/products/productdetail?partno=GRM155R61H104KE14%23"
			(at 204.47 109.22 0)
			(effects
				(font
					(size 1.27 1.27)
					(thickness 0.15)
				)
				(justify left bottom)
				(hide yes)
			)
		)
		(property "Description" ""
			(at 184.15 124.46 0)
			(effects
				(font
					(size 1.27 1.27)
				)
				(hide yes)
			)
		)
		(property "Manufacturer" "Murata"
			(at 204.47 104.14 0)
			(effects
				(font
					(size 1.27 1.27)
					(thickness 0.15)
				)
				(justify left bottom)
				(hide yes)
			)
		)
		(property "MPN" "GRM155R61H104KE14D"
			(at 204.47 106.68 0)
			(effects
				(font
					(size 1.27 1.27)
					(thickness 0.15)
				)
				(justify left bottom)
				(hide yes)
			)
		)
		(property "Val" "100n"
			(at 182.88 125.73 0)
			(effects
				(font
					(size 1.27 1.27)
					(thickness 0.15)
				)
			)
		)
		(property "License" "Apache-2.0"
			(at 204.47 101.6 0)
			(effects
				(font
					(size 1.27 1.27)
					(thickness 0.15)
				)
				(justify left bottom)
				(hide yes)
			)
		)
		(property "Author" "Antmicro"
			(at 204.47 99.06 0)
			(effects
				(font
					(size 1.27 1.27)
					(thickness 0.15)
				)
				(justify left bottom)
				(hide yes)
			)
		)
		(property "Voltage" "50V"
			(at 204.47 96.52 0)
			(effects
				(font
					(size 1.27 1.27)
				)
				(justify left bottom)
				(hide yes)
			)
		)
		(property "Dielectric" "X5R"
			(at 204.47 93.98 0)
			(effects
				(font
					(size 1.27 1.27)
				)
				(justify left bottom)
				(hide yes)
			)
		)
		(pin "1"
		)
		(pin "2"
		)
		(instances
			(project "jetson-orin-baseboard"
				(path ""
					(reference "C141")
					(unit 1)
				)
			)
		)
	)
	(symbol
		(lib_id "antmicroCapacitors0402:C_100n_0402")
		(at 375.92 41.91 90)
		(mirror x)
		(unit 1)
		(exclude_from_sim no)
		(in_bom yes)
		(on_board yes)
		(dnp no)
		(property "Reference" "C65"
			(at 377.825 43.18 90)
			(effects
				(font
					(size 1.27 1.27)
				)
				(justify right)
			)
		)
		(property "Value" "C_100n_0402"
			(at 386.08 62.23 0)
			(effects
				(font
					(size 1.27 1.27)
					(thickness 0.15)
				)
				(justify left bottom)
				(hide yes)
			)
		)
		(property "Footprint" "antmicro-footprints:C_0402_1005Metric"
			(at 388.62 62.23 0)
			(effects
				(font
					(size 1.27 1.27)
					(thickness 0.15)
				)
				(justify left bottom)
				(hide yes)
			)
		)
		(property "Datasheet" "https://www.murata.com/products/productdetail?partno=GRM155R61H104KE14%23"
			(at 391.16 62.23 0)
			(effects
				(font
					(size 1.27 1.27)
					(thickness 0.15)
				)
				(justify left bottom)
				(hide yes)
			)
		)
		(property "Description" ""
			(at 375.92 41.91 0)
			(effects
				(font
					(size 1.27 1.27)
				)
				(hide yes)
			)
		)
		(property "MPN" "GRM155R61H104KE14D"
			(at 393.7 62.23 0)
			(effects
				(font
					(size 1.27 1.27)
					(thickness 0.15)
				)
				(justify left bottom)
				(hide yes)
			)
		)
		(property "Manufacturer" "Murata"
			(at 396.24 62.23 0)
			(effects
				(font
					(size 1.27 1.27)
					(thickness 0.15)
				)
				(justify left bottom)
				(hide yes)
			)
		)
		(property "Val" "100n"
			(at 377.825 45.72 90)
			(effects
				(font
					(size 1.27 1.27)
					(thickness 0.15)
				)
				(justify right)
			)
		)
		(property "License" "Apache-2.0"
			(at 398.78 62.23 0)
			(effects
				(font
					(size 1.27 1.27)
					(thickness 0.15)
				)
				(justify left bottom)
				(hide yes)
			)
		)
		(property "Author" "Antmicro"
			(at 401.32 62.23 0)
			(effects
				(font
					(size 1.27 1.27)
					(thickness 0.15)
				)
				(justify left bottom)
				(hide yes)
			)
		)
		(property "Voltage" "50V"
			(at 403.86 62.23 0)
			(effects
				(font
					(size 1.27 1.27)
				)
				(justify left bottom)
				(hide yes)
			)
		)
		(property "Dielectric" "X5R"
			(at 406.4 62.23 0)
			(effects
				(font
					(size 1.27 1.27)
				)
				(justify left bottom)
				(hide yes)
			)
		)
		(pin "1"
		)
		(pin "2"
		)
		(instances
			(project "jetson-orin-baseboard"
				(path ""
					(reference "C65")
					(unit 1)
				)
			)
		)
	)
	(symbol
		(lib_id "antmicroResistors0402:R_1k_0402")
		(at 262.89 149.86 0)
		(unit 1)
		(exclude_from_sim no)
		(in_bom no)
		(on_board yes)
		(dnp yes)
		(property "Reference" "R89"
			(at 268.605 149.225 0)
			(effects
				(font
					(size 1.27 1.27)
				)
				(justify left bottom)
			)
		)
		(property "Value" "R_1k_0402"
			(at 283.21 162.56 0)
			(effects
				(font
					(size 1.27 1.27)
					(thickness 0.15)
				)
				(justify left bottom)
				(hide yes)
			)
		)
		(property "Footprint" "antmicro-footprints:R_0402_1005Metric"
			(at 283.21 165.1 0)
			(effects
				(font
					(size 1.27 1.27)
					(thickness 0.15)
				)
				(justify left bottom)
				(hide yes)
			)
		)
		(property "Datasheet" "https://www.bourns.com/docs/product-datasheets/cr.pdf"
			(at 283.21 167.64 0)
			(effects
				(font
					(size 1.27 1.27)
					(thickness 0.15)
				)
				(justify left bottom)
				(hide yes)
			)
		)
		(property "Description" ""
			(at 262.89 149.86 0)
			(effects
				(font
					(size 1.27 1.27)
				)
				(hide yes)
			)
		)
		(property "Manufacturer" "Bourns"
			(at 283.21 172.72 0)
			(effects
				(font
					(size 1.27 1.27)
					(thickness 0.15)
				)
				(justify left bottom)
				(hide yes)
			)
		)
		(property "MPN" "CR0402-FX-1001GLF"
			(at 283.21 170.18 0)
			(effects
				(font
					(size 1.27 1.27)
					(thickness 0.15)
				)
				(justify left bottom)
				(hide yes)
			)
		)
		(property "Val" "1k"
			(at 260.35 149.225 0)
			(effects
				(font
					(size 1.27 1.27)
					(thickness 0.15)
				)
				(justify left bottom)
			)
		)
		(property "License" "Apache-2.0"
			(at 283.21 175.26 0)
			(effects
				(font
					(size 1.27 1.27)
					(thickness 0.15)
				)
				(justify left bottom)
				(hide yes)
			)
		)
		(property "Author" "Antmicro"
			(at 283.21 177.8 0)
			(effects
				(font
					(size 1.27 1.27)
					(thickness 0.15)
				)
				(justify left bottom)
				(hide yes)
			)
		)
		(property "Tolerance" "1%"
			(at 283.21 160.02 0)
			(effects
				(font
					(size 1.27 1.27)
				)
				(justify left bottom)
				(hide yes)
			)
		)
		(pin "1"
		)
		(pin "2"
		)
		(instances
			(project "jetson-orin-baseboard"
				(path ""
					(reference "R89")
					(unit 1)
				)
			)
		)
	)
	(symbol
		(lib_id "antmicroResistors0402:R_1k_0402")
		(at 262.89 154.94 0)
		(unit 1)
		(exclude_from_sim no)
		(in_bom no)
		(on_board yes)
		(dnp yes)
		(property "Reference" "R91"
			(at 268.605 154.305 0)
			(effects
				(font
					(size 1.27 1.27)
				)
				(justify left bottom)
			)
		)
		(property "Value" "R_1k_0402"
			(at 283.21 167.64 0)
			(effects
				(font
					(size 1.27 1.27)
					(thickness 0.15)
				)
				(justify left bottom)
				(hide yes)
			)
		)
		(property "Footprint" "antmicro-footprints:R_0402_1005Metric"
			(at 283.21 170.18 0)
			(effects
				(font
					(size 1.27 1.27)
					(thickness 0.15)
				)
				(justify left bottom)
				(hide yes)
			)
		)
		(property "Datasheet" "https://www.bourns.com/docs/product-datasheets/cr.pdf"
			(at 283.21 172.72 0)
			(effects
				(font
					(size 1.27 1.27)
					(thickness 0.15)
				)
				(justify left bottom)
				(hide yes)
			)
		)
		(property "Description" ""
			(at 262.89 154.94 0)
			(effects
				(font
					(size 1.27 1.27)
				)
				(hide yes)
			)
		)
		(property "Manufacturer" "Bourns"
			(at 283.21 177.8 0)
			(effects
				(font
					(size 1.27 1.27)
					(thickness 0.15)
				)
				(justify left bottom)
				(hide yes)
			)
		)
		(property "MPN" "CR0402-FX-1001GLF"
			(at 283.21 175.26 0)
			(effects
				(font
					(size 1.27 1.27)
					(thickness 0.15)
				)
				(justify left bottom)
				(hide yes)
			)
		)
		(property "Val" "1k"
			(at 260.35 154.305 0)
			(effects
				(font
					(size 1.27 1.27)
					(thickness 0.15)
				)
				(justify left bottom)
			)
		)
		(property "License" "Apache-2.0"
			(at 283.21 180.34 0)
			(effects
				(font
					(size 1.27 1.27)
					(thickness 0.15)
				)
				(justify left bottom)
				(hide yes)
			)
		)
		(property "Author" "Antmicro"
			(at 283.21 182.88 0)
			(effects
				(font
					(size 1.27 1.27)
					(thickness 0.15)
				)
				(justify left bottom)
				(hide yes)
			)
		)
		(property "Tolerance" "1%"
			(at 283.21 165.1 0)
			(effects
				(font
					(size 1.27 1.27)
				)
				(justify left bottom)
				(hide yes)
			)
		)
		(pin "1"
		)
		(pin "2"
		)
		(instances
			(project "jetson-orin-baseboard"
				(path ""
					(reference "R91")
					(unit 1)
				)
			)
		)
	)
	(symbol
		(lib_id "antmicroCapacitors0402:C_1u_25V_0402")
		(at 386.08 46.99 90)
		(unit 1)
		(exclude_from_sim no)
		(in_bom yes)
		(on_board yes)
		(dnp no)
		(property "Reference" "C149"
			(at 387.985 43.18 90)
			(effects
				(font
					(size 1.27 1.27)
				)
				(justify right)
			)
		)
		(property "Value" "C_1u_25V_0402"
			(at 396.24 26.67 0)
			(effects
				(font
					(size 1.27 1.27)
					(thickness 0.15)
				)
				(justify left bottom)
				(hide yes)
			)
		)
		(property "Footprint" "antmicro-footprints:C_0402_1005Metric"
			(at 398.78 26.67 0)
			(effects
				(font
					(size 1.27 1.27)
					(thickness 0.15)
				)
				(justify left bottom)
				(hide yes)
			)
		)
		(property "Datasheet" "https://www.murata.com/products/productdetail?partno=GRM155R61E105KE11%23"
			(at 401.32 26.67 0)
			(effects
				(font
					(size 1.27 1.27)
					(thickness 0.15)
				)
				(justify left bottom)
				(hide yes)
			)
		)
		(property "Description" ""
			(at 386.08 46.99 0)
			(effects
				(font
					(size 1.27 1.27)
				)
				(hide yes)
			)
		)
		(property "Manufacturer" "Murata"
			(at 406.4 26.67 0)
			(effects
				(font
					(size 1.27 1.27)
					(thickness 0.15)
				)
				(justify left bottom)
				(hide yes)
			)
		)
		(property "MPN" "GRM155R61E105KE11J"
			(at 403.86 26.67 0)
			(effects
				(font
					(size 1.27 1.27)
					(thickness 0.15)
				)
				(justify left bottom)
				(hide yes)
			)
		)
		(property "Val" "1u"
			(at 387.985 45.72 90)
			(effects
				(font
					(size 1.27 1.27)
					(thickness 0.15)
				)
				(justify right)
			)
		)
		(property "License" "Apache-2.0"
			(at 408.94 26.67 0)
			(effects
				(font
					(size 1.27 1.27)
					(thickness 0.15)
				)
				(justify left bottom)
				(hide yes)
			)
		)
		(property "Author" "Antmicro"
			(at 411.48 26.67 0)
			(effects
				(font
					(size 1.27 1.27)
					(thickness 0.15)
				)
				(justify left bottom)
				(hide yes)
			)
		)
		(property "Voltage" "25V"
			(at 414.02 26.67 0)
			(effects
				(font
					(size 1.27 1.27)
				)
				(justify left bottom)
				(hide yes)
			)
		)
		(property "Dielectric" "X5R"
			(at 416.56 26.67 0)
			(effects
				(font
					(size 1.27 1.27)
				)
				(justify left bottom)
				(hide yes)
			)
		)
		(pin "1"
		)
		(pin "2"
		)
		(instances
			(project "jetson-orin-baseboard"
				(path ""
					(reference "C149")
					(unit 1)
				)
			)
		)
	)
	(symbol
		(lib_name "GND_3")
		(lib_id "antmicropower:GND")
		(at 288.29 60.96 0)
		(mirror y)
		(unit 1)
		(exclude_from_sim no)
		(in_bom yes)
		(on_board yes)
		(dnp no)
		(property "Reference" "#PWR088"
			(at 288.29 67.31 0)
			(effects
				(font
					(size 1.27 1.27)
				)
				(justify left bottom)
				(hide yes)
			)
		)
		(property "Value" "GND"
			(at 288.29 64.77 0)
			(effects
				(font
					(size 1.27 1.27)
					(thickness 0.15)
				)
			)
		)
		(property "Footprint" ""
			(at 279.4 68.58 0)
			(effects
				(font
					(size 1.27 1.27)
					(thickness 0.15)
				)
				(justify left bottom)
				(hide yes)
			)
		)
		(property "Datasheet" ""
			(at 279.4 73.66 0)
			(effects
				(font
					(size 1.27 1.27)
					(thickness 0.15)
				)
				(justify left bottom)
				(hide yes)
			)
		)
		(property "Description" ""
			(at 288.29 60.96 0)
			(effects
				(font
					(size 1.27 1.27)
				)
				(hide yes)
			)
		)
		(property "Author" "Antmicro"
			(at 279.4 68.58 0)
			(effects
				(font
					(size 1.27 1.27)
					(thickness 0.15)
				)
				(justify left bottom)
				(hide yes)
			)
		)
		(property "License" "Apache-2.0"
			(at 279.4 71.12 0)
			(effects
				(font
					(size 1.27 1.27)
					(thickness 0.15)
				)
				(justify left bottom)
				(hide yes)
			)
		)
		(pin "1"
		)
		(instances
			(project "jetson-orin-baseboard"
				(path ""
					(reference "#PWR088")
					(unit 1)
				)
			)
		)
	)
	(symbol
		(lib_id "antmicroResistors0402:R_100k_0402")
		(at 170.18 149.86 270)
		(unit 1)
		(exclude_from_sim no)
		(in_bom yes)
		(on_board yes)
		(dnp no)
		(fields_autoplaced yes)
		(property "Reference" "R205"
			(at 172.72 151.13 90)
			(effects
				(font
					(size 1.27 1.27)
				)
				(justify left)
			)
		)
		(property "Value" "R_100k_0402"
			(at 157.48 170.18 0)
			(effects
				(font
					(size 1.27 1.27)
					(thickness 0.15)
				)
				(justify left bottom)
				(hide yes)
			)
		)
		(property "Footprint" "antmicro-footprints:R_0402_1005Metric"
			(at 154.94 170.18 0)
			(effects
				(font
					(size 1.27 1.27)
					(thickness 0.15)
				)
				(justify left bottom)
				(hide yes)
			)
		)
		(property "Datasheet" "https://www.bourns.com/docs/product-datasheets/cr.pdf"
			(at 152.4 170.18 0)
			(effects
				(font
					(size 1.27 1.27)
					(thickness 0.15)
				)
				(justify left bottom)
				(hide yes)
			)
		)
		(property "Description" ""
			(at 170.18 149.86 0)
			(effects
				(font
					(size 1.27 1.27)
				)
				(hide yes)
			)
		)
		(property "Manufacturer" "Bourns"
			(at 147.32 170.18 0)
			(effects
				(font
					(size 1.27 1.27)
					(thickness 0.15)
				)
				(justify left bottom)
				(hide yes)
			)
		)
		(property "MPN" "CR0402-FX-1003GLF"
			(at 149.86 170.18 0)
			(effects
				(font
					(size 1.27 1.27)
					(thickness 0.15)
				)
				(justify left bottom)
				(hide yes)
			)
		)
		(property "Val" "100k"
			(at 172.72 153.67 90)
			(effects
				(font
					(size 1.27 1.27)
					(thickness 0.15)
				)
				(justify left)
			)
		)
		(property "License" "Apache-2.0"
			(at 144.78 170.18 0)
			(effects
				(font
					(size 1.27 1.27)
					(thickness 0.15)
				)
				(justify left bottom)
				(hide yes)
			)
		)
		(property "Author" "Antmicro"
			(at 142.24 170.18 0)
			(effects
				(font
					(size 1.27 1.27)
					(thickness 0.15)
				)
				(justify left bottom)
				(hide yes)
			)
		)
		(property "Tolerance" "1%"
			(at 160.02 170.18 0)
			(effects
				(font
					(size 1.27 1.27)
				)
				(justify left bottom)
				(hide yes)
			)
		)
		(pin "1"
		)
		(pin "2"
		)
		(instances
			(project "jetson-orin-baseboard"
				(path ""
					(reference "R205")
					(unit 1)
				)
			)
		)
	)
	(symbol
		(lib_name "TP_0.75mm_SMD_2")
		(lib_id "antmicroTestPoints:TP_0.75mm_SMD")
		(at 105.41 104.14 0)
		(unit 1)
		(exclude_from_sim no)
		(in_bom no)
		(on_board yes)
		(dnp no)
		(property "Reference" "TP18"
			(at 109.22 104.775 0)
			(effects
				(font
					(size 1.27 1.27)
				)
				(justify left bottom)
			)
		)
		(property "Value" "TP_0.75mm_SMD"
			(at 115.57 107.95 0)
			(effects
				(font
					(size 1.27 1.27)
					(thickness 0.15)
				)
				(justify left bottom)
				(hide yes)
			)
		)
		(property "Footprint" "antmicro-footprints:TP_SMD_0.75mm"
			(at 115.57 110.49 0)
			(effects
				(font
					(size 1.27 1.27)
					(thickness 0.15)
				)
				(justify left bottom)
				(hide yes)
			)
		)
		(property "Datasheet" ""
			(at 123.19 116.84 0)
			(effects
				(font
					(size 1.27 1.27)
					(thickness 0.15)
				)
				(justify left bottom)
				(hide yes)
			)
		)
		(property "Description" ""
			(at 105.41 104.14 0)
			(effects
				(font
					(size 1.27 1.27)
				)
				(hide yes)
			)
		)
		(property "MPN" ""
			(at 116.205 115.57 0)
			(effects
				(font
					(size 1.27 1.27)
					(thickness 0.15)
				)
				(justify left bottom)
				(hide yes)
			)
		)
		(property "Manufacturer" ""
			(at 116.205 110.49 0)
			(effects
				(font
					(size 1.27 1.27)
					(thickness 0.15)
				)
				(justify left bottom)
				(hide yes)
			)
		)
		(property "Author" "Antmicro"
			(at 115.57 113.03 0)
			(effects
				(font
					(size 1.27 1.27)
					(thickness 0.15)
				)
				(justify left bottom)
				(hide yes)
			)
		)
		(property "License" "Apache-2.0"
			(at 115.57 115.57 0)
			(effects
				(font
					(size 1.27 1.27)
					(thickness 0.15)
				)
				(justify left bottom)
				(hide yes)
			)
		)
		(pin "1"
		)
		(instances
			(project "jetson-orin-baseboard"
				(path ""
					(reference "TP18")
					(unit 1)
				)
			)
		)
	)
	(symbol
		(lib_name "GND_3")
		(lib_id "antmicropower:GND")
		(at 370.84 142.24 0)
		(mirror y)
		(unit 1)
		(exclude_from_sim no)
		(in_bom yes)
		(on_board yes)
		(dnp no)
		(property "Reference" "#PWR0104"
			(at 370.84 148.59 0)
			(effects
				(font
					(size 1.27 1.27)
				)
				(justify left bottom)
				(hide yes)
			)
		)
		(property "Value" "GND"
			(at 370.84 146.05 0)
			(effects
				(font
					(size 1.27 1.27)
					(thickness 0.15)
				)
			)
		)
		(property "Footprint" ""
			(at 361.95 149.86 0)
			(effects
				(font
					(size 1.27 1.27)
					(thickness 0.15)
				)
				(justify left bottom)
				(hide yes)
			)
		)
		(property "Datasheet" ""
			(at 361.95 154.94 0)
			(effects
				(font
					(size 1.27 1.27)
					(thickness 0.15)
				)
				(justify left bottom)
				(hide yes)
			)
		)
		(property "Description" ""
			(at 370.84 142.24 0)
			(effects
				(font
					(size 1.27 1.27)
				)
				(hide yes)
			)
		)
		(property "Author" "Antmicro"
			(at 361.95 149.86 0)
			(effects
				(font
					(size 1.27 1.27)
					(thickness 0.15)
				)
				(justify left bottom)
				(hide yes)
			)
		)
		(property "License" "Apache-2.0"
			(at 361.95 152.4 0)
			(effects
				(font
					(size 1.27 1.27)
					(thickness 0.15)
				)
				(justify left bottom)
				(hide yes)
			)
		)
		(pin "1"
		)
		(instances
			(project "jetson-orin-baseboard"
				(path ""
					(reference "#PWR0104")
					(unit 1)
				)
			)
		)
	)
	(symbol
		(lib_name "GND_3")
		(lib_id "antmicropower:GND")
		(at 173.99 208.28 0)
		(mirror y)
		(unit 1)
		(exclude_from_sim no)
		(in_bom yes)
		(on_board yes)
		(dnp no)
		(property "Reference" "#PWR079"
			(at 173.99 214.63 0)
			(effects
				(font
					(size 1.27 1.27)
				)
				(justify left bottom)
				(hide yes)
			)
		)
		(property "Value" "GND"
			(at 173.99 212.09 0)
			(effects
				(font
					(size 1.27 1.27)
					(thickness 0.15)
				)
			)
		)
		(property "Footprint" ""
			(at 165.1 215.9 0)
			(effects
				(font
					(size 1.27 1.27)
					(thickness 0.15)
				)
				(justify left bottom)
				(hide yes)
			)
		)
		(property "Datasheet" ""
			(at 165.1 220.98 0)
			(effects
				(font
					(size 1.27 1.27)
					(thickness 0.15)
				)
				(justify left bottom)
				(hide yes)
			)
		)
		(property "Description" ""
			(at 173.99 208.28 0)
			(effects
				(font
					(size 1.27 1.27)
				)
				(hide yes)
			)
		)
		(property "Author" "Antmicro"
			(at 165.1 215.9 0)
			(effects
				(font
					(size 1.27 1.27)
					(thickness 0.15)
				)
				(justify left bottom)
				(hide yes)
			)
		)
		(property "License" "Apache-2.0"
			(at 165.1 218.44 0)
			(effects
				(font
					(size 1.27 1.27)
					(thickness 0.15)
				)
				(justify left bottom)
				(hide yes)
			)
		)
		(pin "1"
		)
		(instances
			(project "jetson-orin-baseboard"
				(path ""
					(reference "#PWR079")
					(unit 1)
				)
			)
		)
	)
	(symbol
		(lib_name "R_0R_0402_1")
		(lib_id "antmicroResistors0402:R_0R_0402")
		(at 114.3 93.98 180)
		(unit 1)
		(exclude_from_sim no)
		(in_bom no)
		(on_board yes)
		(dnp yes)
		(property "Reference" "R244"
			(at 114.3 93.345 0)
			(effects
				(font
					(size 1.27 1.27)
				)
				(justify right top)
			)
		)
		(property "Value" "R_0R_0402"
			(at 93.98 81.28 0)
			(effects
				(font
					(size 1.27 1.27)
					(thickness 0.15)
				)
				(justify left bottom)
				(hide yes)
			)
		)
		(property "Footprint" "antmicro-footprints:R_0402_1005Metric"
			(at 93.98 78.74 0)
			(effects
				(font
					(size 1.27 1.27)
					(thickness 0.15)
				)
				(justify left bottom)
				(hide yes)
			)
		)
		(property "Datasheet" "https://industrial.panasonic.com/cdbs/www-data/pdf/RDA0000/AOA0000C301.pdf"
			(at 93.98 76.2 0)
			(effects
				(font
					(size 1.27 1.27)
					(thickness 0.15)
				)
				(justify left bottom)
				(hide yes)
			)
		)
		(property "Description" ""
			(at 114.3 93.98 0)
			(effects
				(font
					(size 1.27 1.27)
				)
				(hide yes)
			)
		)
		(property "Manufacturer" "Panasonic"
			(at 93.98 71.12 0)
			(effects
				(font
					(size 1.27 1.27)
					(thickness 0.15)
				)
				(justify left bottom)
				(hide yes)
			)
		)
		(property "MPN" "ERJ2GE0R00X"
			(at 93.98 73.66 0)
			(effects
				(font
					(size 1.27 1.27)
					(thickness 0.15)
				)
				(justify left bottom)
				(hide yes)
			)
		)
		(property "Val" "0R"
			(at 106.68 93.345 0)
			(effects
				(font
					(size 1.27 1.27)
					(thickness 0.15)
				)
				(justify right top)
			)
		)
		(property "License" "Apache-2.0"
			(at 93.98 68.58 0)
			(effects
				(font
					(size 1.27 1.27)
					(thickness 0.15)
				)
				(justify left bottom)
				(hide yes)
			)
		)
		(property "Author" "Antmicro"
			(at 93.98 66.04 0)
			(effects
				(font
					(size 1.27 1.27)
					(thickness 0.15)
				)
				(justify left bottom)
				(hide yes)
			)
		)
		(property "Tolerance" "~"
			(at 93.98 83.82 0)
			(effects
				(font
					(size 1.27 1.27)
				)
				(justify left bottom)
				(hide yes)
			)
		)
		(property "Current" "1A"
			(at 93.98 63.5 0)
			(effects
				(font
					(size 1.27 1.27)
					(thickness 0.15)
				)
				(justify left bottom)
				(hide yes)
			)
		)
		(pin "1"
		)
		(pin "2"
		)
		(instances
			(project "jetson-orin-baseboard"
				(path ""
					(reference "R244")
					(unit 1)
				)
			)
		)
	)
	(symbol
		(lib_id "antmicroPMICPowerDistributionSwitchesLoadDrivers:AP22615A_TSOT26")
		(at 292.1 48.26 0)
		(unit 1)
		(exclude_from_sim no)
		(in_bom yes)
		(on_board yes)
		(dnp no)
		(property "Reference" "U12"
			(at 299.72 41.91 0)
			(effects
				(font
					(size 1.27 1.27)
				)
			)
		)
		(property "Value" "AP22615A_TSOT26"
			(at 322.58 53.34 0)
			(effects
				(font
					(size 1.27 1.27)
					(thickness 0.15)
				)
				(justify left bottom)
				(hide yes)
			)
		)
		(property "Footprint" "antmicro-footprints:TSOT23-6"
			(at 322.58 55.88 0)
			(effects
				(font
					(size 1.27 1.27)
					(thickness 0.15)
				)
				(justify left bottom)
				(hide yes)
			)
		)
		(property "Datasheet" "https://www.mouser.com/datasheet/2/115/DIOD_S_A0008958405_1-2543193.pdf"
			(at 322.58 58.42 0)
			(effects
				(font
					(size 1.27 1.27)
					(thickness 0.15)
				)
				(justify left bottom)
				(hide yes)
			)
		)
		(property "Description" ""
			(at 292.1 48.26 0)
			(effects
				(font
					(size 1.27 1.27)
				)
				(hide yes)
			)
		)
		(property "MPN" "AP22615AWU-7"
			(at 299.72 44.45 0)
			(effects
				(font
					(size 1.27 1.27)
					(thickness 0.15)
				)
			)
		)
		(property "Manufacturer" "Diodes Incorporated"
			(at 322.58 63.5 0)
			(effects
				(font
					(size 1.27 1.27)
					(thickness 0.15)
				)
				(justify left bottom)
				(hide yes)
			)
		)
		(property "Author" "Antmicro"
			(at 322.58 66.04 0)
			(effects
				(font
					(size 1.27 1.27)
					(thickness 0.15)
				)
				(justify left bottom)
				(hide yes)
			)
		)
		(property "License" "Apache-2.0"
			(at 322.58 68.58 0)
			(effects
				(font
					(size 1.27 1.27)
					(thickness 0.15)
				)
				(justify left bottom)
				(hide yes)
			)
		)
		(pin "1"
		)
		(pin "2"
		)
		(pin "3"
		)
		(pin "4"
		)
		(pin "5"
		)
		(pin "6"
		)
		(instances
			(project "jetson-orin-baseboard"
				(path ""
					(reference "U12")
					(unit 1)
				)
			)
		)
	)
	(symbol
		(lib_name "DF2S30FS_SOD_1")
		(lib_id "antmicroTVSDiodes:DF2S30FS_SOD")
		(at 337.82 191.77 270)
		(unit 1)
		(exclude_from_sim no)
		(in_bom yes)
		(on_board yes)
		(dnp no)
		(fields_autoplaced yes)
		(property "Reference" "D6"
			(at 339.725 193.04 90)
			(effects
				(font
					(size 1.27 1.27)
				)
				(justify left)
			)
		)
		(property "Value" "DF2S30FS_SOD"
			(at 322.58 213.36 0)
			(effects
				(font
					(size 1.27 1.27)
					(thickness 0.15)
				)
				(justify left bottom)
				(hide yes)
			)
		)
		(property "Footprint" "antmicro-footprints:SOD-923"
			(at 330.2 213.36 0)
			(effects
				(font
					(size 1.27 1.27)
					(thickness 0.15)
				)
				(justify left bottom)
				(hide yes)
			)
		)
		(property "Datasheet" "https://toshiba.semicon-storage.com/info/DF2S30FS_datasheet_en_20211216.pdf?did=11156&prodName=DF2S30FS"
			(at 327.66 213.36 0)
			(effects
				(font
					(size 1.27 1.27)
					(thickness 0.15)
				)
				(justify left bottom)
				(hide yes)
			)
		)
		(property "Description" ""
			(at 337.82 191.77 0)
			(effects
				(font
					(size 1.27 1.27)
				)
				(hide yes)
			)
		)
		(property "Manufacturer" "Toshiba"
			(at 325.12 213.36 0)
			(effects
				(font
					(size 1.27 1.27)
					(thickness 0.15)
				)
				(justify left bottom)
				(hide yes)
			)
		)
		(property "MPN" "DF2S30FS"
			(at 339.725 195.58 90)
			(effects
				(font
					(size 1.27 1.27)
					(thickness 0.15)
				)
				(justify left)
			)
		)
		(property "Author" "Antmicro"
			(at 320.04 213.36 0)
			(effects
				(font
					(size 1.27 1.27)
					(thickness 0.15)
				)
				(justify left bottom)
				(hide yes)
			)
		)
		(property "License" "Apache-2.0"
			(at 317.5 213.36 0)
			(effects
				(font
					(size 1.27 1.27)
					(thickness 0.15)
				)
				(justify left bottom)
				(hide yes)
			)
		)
		(pin "1"
		)
		(pin "2"
		)
		(instances
			(project "jetson-orin-baseboard"
				(path ""
					(reference "D6")
					(unit 1)
				)
			)
		)
	)
	(symbol
		(lib_name "R_0R_0402_11")
		(lib_id "antmicroResistors0402:R_0R_0402")
		(at 185.42 207.01 90)
		(unit 1)
		(exclude_from_sim no)
		(in_bom no)
		(on_board yes)
		(dnp yes)
		(property "Reference" "R144"
			(at 186.69 203.2 90)
			(effects
				(font
					(size 1.27 1.27)
				)
				(justify right)
			)
		)
		(property "Value" "R_0R_0402"
			(at 198.12 186.69 0)
			(effects
				(font
					(size 1.27 1.27)
					(thickness 0.15)
				)
				(justify left bottom)
				(hide yes)
			)
		)
		(property "Footprint" "antmicro-footprints:R_0402_1005Metric"
			(at 200.66 186.69 0)
			(effects
				(font
					(size 1.27 1.27)
					(thickness 0.15)
				)
				(justify left bottom)
				(hide yes)
			)
		)
		(property "Datasheet" "https://industrial.panasonic.com/cdbs/www-data/pdf/RDA0000/AOA0000C301.pdf"
			(at 203.2 186.69 0)
			(effects
				(font
					(size 1.27 1.27)
					(thickness 0.15)
				)
				(justify left bottom)
				(hide yes)
			)
		)
		(property "Description" ""
			(at 185.42 207.01 0)
			(effects
				(font
					(size 1.27 1.27)
				)
				(hide yes)
			)
		)
		(property "Manufacturer" "Panasonic"
			(at 208.28 186.69 0)
			(effects
				(font
					(size 1.27 1.27)
					(thickness 0.15)
				)
				(justify left bottom)
				(hide yes)
			)
		)
		(property "MPN" "ERJ2GE0R00X"
			(at 205.74 186.69 0)
			(effects
				(font
					(size 1.27 1.27)
					(thickness 0.15)
				)
				(justify left bottom)
				(hide yes)
			)
		)
		(property "Val" "0R"
			(at 186.69 205.74 90)
			(effects
				(font
					(size 1.27 1.27)
					(thickness 0.15)
				)
				(justify right)
			)
		)
		(property "License" "Apache-2.0"
			(at 210.82 186.69 0)
			(effects
				(font
					(size 1.27 1.27)
					(thickness 0.15)
				)
				(justify left bottom)
				(hide yes)
			)
		)
		(property "Author" "Antmicro"
			(at 213.36 186.69 0)
			(effects
				(font
					(size 1.27 1.27)
					(thickness 0.15)
				)
				(justify left bottom)
				(hide yes)
			)
		)
		(property "Tolerance" "~"
			(at 195.58 186.69 0)
			(effects
				(font
					(size 1.27 1.27)
				)
				(justify left bottom)
				(hide yes)
			)
		)
		(property "Current" "1A"
			(at 215.9 186.69 0)
			(effects
				(font
					(size 1.27 1.27)
					(thickness 0.15)
				)
				(justify left bottom)
				(hide yes)
			)
		)
		(pin "1"
		)
		(pin "2"
		)
		(instances
			(project "jetson-orin-baseboard"
				(path ""
					(reference "R144")
					(unit 1)
				)
			)
		)
	)
	(symbol
		(lib_name "LED_G_0603_LTST-C190GKT_3")
		(lib_id "antmicroLEDIndicationDiscrete:LED_G_0603_LTST-C190GKT")
		(at 120.65 204.47 270)
		(mirror x)
		(unit 1)
		(exclude_from_sim no)
		(in_bom yes)
		(on_board yes)
		(dnp no)
		(fields_autoplaced yes)
		(property "Reference" "D2"
			(at 124.46 200.66 90)
			(effects
				(font
					(size 1.27 1.27)
				)
				(justify left)
			)
		)
		(property "Value" "LED_G_0603_LTST-C190GKT"
			(at 113.03 181.61 0)
			(effects
				(font
					(size 1.27 1.27)
					(thickness 0.15)
				)
				(justify left bottom)
				(hide yes)
			)
		)
		(property "Footprint" "antmicro-footprints:LED_0603_1608Metric_G"
			(at 110.49 181.61 0)
			(effects
				(font
					(size 1.27 1.27)
					(thickness 0.15)
				)
				(justify left bottom)
				(hide yes)
			)
		)
		(property "Datasheet" "https://media.digikey.com/pdf/Data%20Sheets/Lite-On%20PDFs/LTST-C190GKT.pdf"
			(at 107.95 181.61 0)
			(effects
				(font
					(size 1.27 1.27)
					(thickness 0.15)
				)
				(justify left bottom)
				(hide yes)
			)
		)
		(property "Description" ""
			(at 120.65 204.47 0)
			(effects
				(font
					(size 1.27 1.27)
				)
				(hide yes)
			)
		)
		(property "MPN" "LTST-C190GKT"
			(at 105.41 181.61 0)
			(effects
				(font
					(size 1.27 1.27)
					(thickness 0.15)
				)
				(justify left bottom)
				(hide yes)
			)
		)
		(property "Manufacturer" "Lite-On"
			(at 102.87 181.61 0)
			(effects
				(font
					(size 1.27 1.27)
					(thickness 0.15)
				)
				(justify left bottom)
				(hide yes)
			)
		)
		(property "Author" "Antmicro"
			(at 100.33 181.61 0)
			(effects
				(font
					(size 1.27 1.27)
					(thickness 0.15)
				)
				(justify left bottom)
				(hide yes)
			)
		)
		(property "License" "Apache-2.0"
			(at 97.79 181.61 0)
			(effects
				(font
					(size 1.27 1.27)
					(thickness 0.15)
				)
				(justify left bottom)
				(hide yes)
			)
		)
		(property "Color" "Green"
			(at 124.46 203.2 90)
			(effects
				(font
					(size 1.27 1.27)
				)
				(justify left)
			)
		)
		(pin "1"
		)
		(pin "2"
		)
		(instances
			(project "jetson-orin-baseboard"
				(path ""
					(reference "D2")
					(unit 1)
				)
			)
		)
	)
	(symbol
		(lib_id "antmicroResistors0402:R_27R_0402")
		(at 330.2 219.71 0)
		(unit 1)
		(exclude_from_sim no)
		(in_bom yes)
		(on_board yes)
		(dnp no)
		(property "Reference" "R127"
			(at 335.28 219.075 0)
			(effects
				(font
					(size 1.27 1.27)
				)
				(justify left bottom)
			)
		)
		(property "Value" "R_27R_0402"
			(at 350.52 232.41 0)
			(effects
				(font
					(size 1.27 1.27)
					(thickness 0.15)
				)
				(justify left bottom)
				(hide yes)
			)
		)
		(property "Footprint" "antmicro-footprints:R_0402_1005Metric"
			(at 350.52 234.95 0)
			(effects
				(font
					(size 1.27 1.27)
					(thickness 0.15)
				)
				(justify left bottom)
				(hide yes)
			)
		)
		(property "Datasheet" "https://www.bourns.com/docs/product-datasheets/cr.pdf"
			(at 350.52 237.49 0)
			(effects
				(font
					(size 1.27 1.27)
					(thickness 0.15)
				)
				(justify left bottom)
				(hide yes)
			)
		)
		(property "Description" ""
			(at 330.2 219.71 0)
			(effects
				(font
					(size 1.27 1.27)
				)
				(hide yes)
			)
		)
		(property "Manufacturer" "Bourns"
			(at 350.52 242.57 0)
			(effects
				(font
					(size 1.27 1.27)
					(thickness 0.15)
				)
				(justify left bottom)
				(hide yes)
			)
		)
		(property "MPN" "CR0402-FX-27R0GLF"
			(at 350.52 240.03 0)
			(effects
				(font
					(size 1.27 1.27)
					(thickness 0.15)
				)
				(justify left bottom)
				(hide yes)
			)
		)
		(property "Val" "27R"
			(at 326.39 219.075 0)
			(effects
				(font
					(size 1.27 1.27)
					(thickness 0.15)
				)
				(justify left bottom)
			)
		)
		(property "License" "Apache-2.0"
			(at 350.52 245.11 0)
			(effects
				(font
					(size 1.27 1.27)
					(thickness 0.15)
				)
				(justify left bottom)
				(hide yes)
			)
		)
		(property "Author" "Antmicro"
			(at 350.52 247.65 0)
			(effects
				(font
					(size 1.27 1.27)
					(thickness 0.15)
				)
				(justify left bottom)
				(hide yes)
			)
		)
		(property "Tolerance" "1%"
			(at 350.52 229.87 0)
			(effects
				(font
					(size 1.27 1.27)
				)
				(justify left bottom)
				(hide yes)
			)
		)
		(pin "1"
		)
		(pin "2"
		)
		(instances
			(project "jetson-orin-baseboard"
				(path ""
					(reference "R127")
					(unit 1)
				)
			)
		)
	)
	(symbol
		(lib_id "antmicroResistors0402:R_0R_0402")
		(at 273.05 40.64 90)
		(unit 1)
		(exclude_from_sim no)
		(in_bom no)
		(on_board yes)
		(dnp yes)
		(property "Reference" "R158"
			(at 274.32 36.83 90)
			(effects
				(font
					(size 1.27 1.27)
				)
				(justify right)
			)
		)
		(property "Value" "R_0R_0402"
			(at 285.75 20.32 0)
			(effects
				(font
					(size 1.27 1.27)
					(thickness 0.15)
				)
				(justify left bottom)
				(hide yes)
			)
		)
		(property "Footprint" "antmicro-footprints:R_0402_1005Metric"
			(at 288.29 20.32 0)
			(effects
				(font
					(size 1.27 1.27)
					(thickness 0.15)
				)
				(justify left bottom)
				(hide yes)
			)
		)
		(property "Datasheet" "https://industrial.panasonic.com/cdbs/www-data/pdf/RDA0000/AOA0000C301.pdf"
			(at 290.83 20.32 0)
			(effects
				(font
					(size 1.27 1.27)
					(thickness 0.15)
				)
				(justify left bottom)
				(hide yes)
			)
		)
		(property "Description" ""
			(at 273.05 40.64 0)
			(effects
				(font
					(size 1.27 1.27)
				)
				(hide yes)
			)
		)
		(property "Manufacturer" "Panasonic"
			(at 295.91 20.32 0)
			(effects
				(font
					(size 1.27 1.27)
					(thickness 0.15)
				)
				(justify left bottom)
				(hide yes)
			)
		)
		(property "MPN" "ERJ2GE0R00X"
			(at 293.37 20.32 0)
			(effects
				(font
					(size 1.27 1.27)
					(thickness 0.15)
				)
				(justify left bottom)
				(hide yes)
			)
		)
		(property "Val" "0R"
			(at 274.32 39.37 90)
			(effects
				(font
					(size 1.27 1.27)
					(thickness 0.15)
				)
				(justify right)
			)
		)
		(property "License" "Apache-2.0"
			(at 298.45 20.32 0)
			(effects
				(font
					(size 1.27 1.27)
					(thickness 0.15)
				)
				(justify left bottom)
				(hide yes)
			)
		)
		(property "Author" "Antmicro"
			(at 300.99 20.32 0)
			(effects
				(font
					(size 1.27 1.27)
					(thickness 0.15)
				)
				(justify left bottom)
				(hide yes)
			)
		)
		(property "Tolerance" "~"
			(at 283.21 20.32 0)
			(effects
				(font
					(size 1.27 1.27)
				)
				(justify left bottom)
				(hide yes)
			)
		)
		(property "Current" "1A"
			(at 303.53 20.32 0)
			(effects
				(font
					(size 1.27 1.27)
					(thickness 0.15)
				)
				(justify left bottom)
				(hide yes)
			)
		)
		(pin "1"
		)
		(pin "2"
		)
		(instances
			(project "jetson-orin-baseboard"
				(path ""
					(reference "R158")
					(unit 1)
				)
			)
		)
	)
	(symbol
		(lib_name "R_0R_0402_2")
		(lib_id "antmicroResistors0402:R_0R_0402")
		(at 114.3 96.52 180)
		(unit 1)
		(exclude_from_sim no)
		(in_bom yes)
		(on_board yes)
		(dnp no)
		(property "Reference" "R70"
			(at 114.3 95.885 0)
			(effects
				(font
					(size 1.27 1.27)
				)
				(justify right top)
			)
		)
		(property "Value" "R_0R_0402"
			(at 93.98 83.82 0)
			(effects
				(font
					(size 1.27 1.27)
					(thickness 0.15)
				)
				(justify left bottom)
				(hide yes)
			)
		)
		(property "Footprint" "antmicro-footprints:R_0402_1005Metric"
			(at 93.98 81.28 0)
			(effects
				(font
					(size 1.27 1.27)
					(thickness 0.15)
				)
				(justify left bottom)
				(hide yes)
			)
		)
		(property "Datasheet" "https://industrial.panasonic.com/cdbs/www-data/pdf/RDA0000/AOA0000C301.pdf"
			(at 93.98 78.74 0)
			(effects
				(font
					(size 1.27 1.27)
					(thickness 0.15)
				)
				(justify left bottom)
				(hide yes)
			)
		)
		(property "Description" ""
			(at 114.3 96.52 0)
			(effects
				(font
					(size 1.27 1.27)
				)
				(hide yes)
			)
		)
		(property "Manufacturer" "Panasonic"
			(at 93.98 73.66 0)
			(effects
				(font
					(size 1.27 1.27)
					(thickness 0.15)
				)
				(justify left bottom)
				(hide yes)
			)
		)
		(property "MPN" "ERJ2GE0R00X"
			(at 93.98 76.2 0)
			(effects
				(font
					(size 1.27 1.27)
					(thickness 0.15)
				)
				(justify left bottom)
				(hide yes)
			)
		)
		(property "Val" "0R"
			(at 106.68 95.885 0)
			(effects
				(font
					(size 1.27 1.27)
					(thickness 0.15)
				)
				(justify right top)
			)
		)
		(property "License" "Apache-2.0"
			(at 93.98 71.12 0)
			(effects
				(font
					(size 1.27 1.27)
					(thickness 0.15)
				)
				(justify left bottom)
				(hide yes)
			)
		)
		(property "Author" "Antmicro"
			(at 93.98 68.58 0)
			(effects
				(font
					(size 1.27 1.27)
					(thickness 0.15)
				)
				(justify left bottom)
				(hide yes)
			)
		)
		(property "Tolerance" "~"
			(at 93.98 86.36 0)
			(effects
				(font
					(size 1.27 1.27)
				)
				(justify left bottom)
				(hide yes)
			)
		)
		(property "Current" "1A"
			(at 93.98 66.04 0)
			(effects
				(font
					(size 1.27 1.27)
					(thickness 0.15)
				)
				(justify left bottom)
				(hide yes)
			)
		)
		(pin "1"
		)
		(pin "2"
		)
		(instances
			(project "jetson-orin-baseboard"
				(path ""
					(reference "R70")
					(unit 1)
				)
			)
		)
	)
	(symbol
		(lib_id "antmicroCapacitors0402:C_100n_0402")
		(at 181.61 114.3 0)
		(mirror x)
		(unit 1)
		(exclude_from_sim no)
		(in_bom yes)
		(on_board yes)
		(dnp no)
		(property "Reference" "C143"
			(at 187.96 113.03 0)
			(effects
				(font
					(size 1.27 1.27)
				)
			)
		)
		(property "Value" "C_100n_0402"
			(at 201.93 104.14 0)
			(effects
				(font
					(size 1.27 1.27)
					(thickness 0.15)
				)
				(justify left bottom)
				(hide yes)
			)
		)
		(property "Footprint" "antmicro-footprints:C_0402_1005Metric"
			(at 201.93 101.6 0)
			(effects
				(font
					(size 1.27 1.27)
					(thickness 0.15)
				)
				(justify left bottom)
				(hide yes)
			)
		)
		(property "Datasheet" "https://www.murata.com/products/productdetail?partno=GRM155R61H104KE14%23"
			(at 201.93 99.06 0)
			(effects
				(font
					(size 1.27 1.27)
					(thickness 0.15)
				)
				(justify left bottom)
				(hide yes)
			)
		)
		(property "Description" ""
			(at 181.61 114.3 0)
			(effects
				(font
					(size 1.27 1.27)
				)
				(hide yes)
			)
		)
		(property "Manufacturer" "Murata"
			(at 201.93 93.98 0)
			(effects
				(font
					(size 1.27 1.27)
					(thickness 0.15)
				)
				(justify left bottom)
				(hide yes)
			)
		)
		(property "MPN" "GRM155R61H104KE14D"
			(at 201.93 96.52 0)
			(effects
				(font
					(size 1.27 1.27)
					(thickness 0.15)
				)
				(justify left bottom)
				(hide yes)
			)
		)
		(property "Val" "100n"
			(at 180.34 115.57 0)
			(effects
				(font
					(size 1.27 1.27)
					(thickness 0.15)
				)
			)
		)
		(property "License" "Apache-2.0"
			(at 201.93 91.44 0)
			(effects
				(font
					(size 1.27 1.27)
					(thickness 0.15)
				)
				(justify left bottom)
				(hide yes)
			)
		)
		(property "Author" "Antmicro"
			(at 201.93 88.9 0)
			(effects
				(font
					(size 1.27 1.27)
					(thickness 0.15)
				)
				(justify left bottom)
				(hide yes)
			)
		)
		(property "Voltage" "50V"
			(at 201.93 86.36 0)
			(effects
				(font
					(size 1.27 1.27)
				)
				(justify left bottom)
				(hide yes)
			)
		)
		(property "Dielectric" "X5R"
			(at 201.93 83.82 0)
			(effects
				(font
					(size 1.27 1.27)
				)
				(justify left bottom)
				(hide yes)
			)
		)
		(pin "1"
		)
		(pin "2"
		)
		(instances
			(project "jetson-orin-baseboard"
				(path ""
					(reference "C143")
					(unit 1)
				)
			)
		)
	)
	(symbol
		(lib_name "GND_3")
		(lib_id "antmicropower:GND")
		(at 21.59 57.15 0)
		(mirror y)
		(unit 1)
		(exclude_from_sim no)
		(in_bom yes)
		(on_board yes)
		(dnp no)
		(property "Reference" "#PWR050"
			(at 21.59 63.5 0)
			(effects
				(font
					(size 1.27 1.27)
				)
				(justify left bottom)
				(hide yes)
			)
		)
		(property "Value" "GND"
			(at 21.59 60.96 0)
			(effects
				(font
					(size 1.27 1.27)
					(thickness 0.15)
				)
			)
		)
		(property "Footprint" ""
			(at 12.7 64.77 0)
			(effects
				(font
					(size 1.27 1.27)
					(thickness 0.15)
				)
				(justify left bottom)
				(hide yes)
			)
		)
		(property "Datasheet" ""
			(at 12.7 69.85 0)
			(effects
				(font
					(size 1.27 1.27)
					(thickness 0.15)
				)
				(justify left bottom)
				(hide yes)
			)
		)
		(property "Description" ""
			(at 21.59 57.15 0)
			(effects
				(font
					(size 1.27 1.27)
				)
				(hide yes)
			)
		)
		(property "Author" "Antmicro"
			(at 12.7 64.77 0)
			(effects
				(font
					(size 1.27 1.27)
					(thickness 0.15)
				)
				(justify left bottom)
				(hide yes)
			)
		)
		(property "License" "Apache-2.0"
			(at 12.7 67.31 0)
			(effects
				(font
					(size 1.27 1.27)
					(thickness 0.15)
				)
				(justify left bottom)
				(hide yes)
			)
		)
		(pin "1"
		)
		(instances
			(project "jetson-orin-baseboard"
				(path ""
					(reference "#PWR050")
					(unit 1)
				)
			)
		)
	)
	(symbol
		(lib_name "R_4k7_0402_4")
		(lib_id "antmicroResistors0402:R_4k7_0402")
		(at 132.08 128.27 180)
		(unit 1)
		(exclude_from_sim no)
		(in_bom yes)
		(on_board yes)
		(dnp no)
		(property "Reference" "R81"
			(at 132.08 127.635 0)
			(effects
				(font
					(size 1.27 1.27)
				)
				(justify right top)
			)
		)
		(property "Value" "R_4k7_0402"
			(at 111.76 115.57 0)
			(effects
				(font
					(size 1.27 1.27)
					(thickness 0.15)
				)
				(justify left bottom)
				(hide yes)
			)
		)
		(property "Footprint" "antmicro-footprints:R_0402_1005Metric"
			(at 111.76 113.03 0)
			(effects
				(font
					(size 1.27 1.27)
					(thickness 0.15)
				)
				(justify left bottom)
				(hide yes)
			)
		)
		(property "Datasheet" "https://www.bourns.com/docs/product-datasheets/cr.pdf"
			(at 111.76 110.49 0)
			(effects
				(font
					(size 1.27 1.27)
					(thickness 0.15)
				)
				(justify left bottom)
				(hide yes)
			)
		)
		(property "Description" ""
			(at 132.08 128.27 0)
			(effects
				(font
					(size 1.27 1.27)
				)
				(hide yes)
			)
		)
		(property "Manufacturer" "Bourns"
			(at 111.76 105.41 0)
			(effects
				(font
					(size 1.27 1.27)
					(thickness 0.15)
				)
				(justify left bottom)
				(hide yes)
			)
		)
		(property "MPN" "CR0402-FX-4701GLF"
			(at 111.76 107.95 0)
			(effects
				(font
					(size 1.27 1.27)
					(thickness 0.15)
				)
				(justify left bottom)
				(hide yes)
			)
		)
		(property "Val" "4k7"
			(at 123.19 127.635 0)
			(effects
				(font
					(size 1.27 1.27)
					(thickness 0.15)
				)
				(justify right top)
			)
		)
		(property "License" "Apache-2.0"
			(at 111.76 102.87 0)
			(effects
				(font
					(size 1.27 1.27)
					(thickness 0.15)
				)
				(justify left bottom)
				(hide yes)
			)
		)
		(property "Author" "Antmicro"
			(at 111.76 100.33 0)
			(effects
				(font
					(size 1.27 1.27)
					(thickness 0.15)
				)
				(justify left bottom)
				(hide yes)
			)
		)
		(property "Tolerance" "1%"
			(at 111.76 118.11 0)
			(effects
				(font
					(size 1.27 1.27)
				)
				(justify left bottom)
				(hide yes)
			)
		)
		(pin "1"
		)
		(pin "2"
		)
		(instances
			(project "jetson-orin-baseboard"
				(path ""
					(reference "R81")
					(unit 1)
				)
			)
		)
	)
	(symbol
		(lib_name "C_100n_0402_6")
		(lib_id "antmicroCapacitors0402:C_100n_0402")
		(at 327.66 191.77 270)
		(unit 1)
		(exclude_from_sim no)
		(in_bom yes)
		(on_board yes)
		(dnp no)
		(property "Reference" "C64"
			(at 329.565 193.04 90)
			(effects
				(font
					(size 1.27 1.27)
				)
				(justify left)
			)
		)
		(property "Value" "C_100n_0402"
			(at 317.5 212.09 0)
			(effects
				(font
					(size 1.27 1.27)
					(thickness 0.15)
				)
				(justify left bottom)
				(hide yes)
			)
		)
		(property "Footprint" "antmicro-footprints:C_0402_1005Metric"
			(at 314.96 212.09 0)
			(effects
				(font
					(size 1.27 1.27)
					(thickness 0.15)
				)
				(justify left bottom)
				(hide yes)
			)
		)
		(property "Datasheet" "https://www.murata.com/products/productdetail?partno=GRM155R61H104KE14%23"
			(at 312.42 212.09 0)
			(effects
				(font
					(size 1.27 1.27)
					(thickness 0.15)
				)
				(justify left bottom)
				(hide yes)
			)
		)
		(property "Description" ""
			(at 327.66 191.77 0)
			(effects
				(font
					(size 1.27 1.27)
				)
				(hide yes)
			)
		)
		(property "MPN" "GRM155R61H104KE14D"
			(at 309.88 212.09 0)
			(effects
				(font
					(size 1.27 1.27)
					(thickness 0.15)
				)
				(justify left bottom)
				(hide yes)
			)
		)
		(property "Manufacturer" "Murata"
			(at 307.34 212.09 0)
			(effects
				(font
					(size 1.27 1.27)
					(thickness 0.15)
				)
				(justify left bottom)
				(hide yes)
			)
		)
		(property "Val" "100n"
			(at 329.565 195.58 90)
			(effects
				(font
					(size 1.27 1.27)
					(thickness 0.15)
				)
				(justify left)
			)
		)
		(property "License" "Apache-2.0"
			(at 304.8 212.09 0)
			(effects
				(font
					(size 1.27 1.27)
					(thickness 0.15)
				)
				(justify left bottom)
				(hide yes)
			)
		)
		(property "Author" "Antmicro"
			(at 302.26 212.09 0)
			(effects
				(font
					(size 1.27 1.27)
					(thickness 0.15)
				)
				(justify left bottom)
				(hide yes)
			)
		)
		(property "Voltage" "50V"
			(at 299.72 212.09 0)
			(effects
				(font
					(size 1.27 1.27)
				)
				(justify left bottom)
				(hide yes)
			)
		)
		(property "Dielectric" "X5R"
			(at 297.18 212.09 0)
			(effects
				(font
					(size 1.27 1.27)
				)
				(justify left bottom)
				(hide yes)
			)
		)
		(pin "1"
		)
		(pin "2"
		)
		(instances
			(project "jetson-orin-baseboard"
				(path ""
					(reference "C64")
					(unit 1)
				)
			)
		)
	)
	(symbol
		(lib_id "antmicroTestPoints:TP_0.75mm_SMD")
		(at 355.6 40.64 180)
		(unit 1)
		(exclude_from_sim no)
		(in_bom no)
		(on_board yes)
		(dnp no)
		(property "Reference" "TP17"
			(at 351.79 40.64 0)
			(effects
				(font
					(size 1.27 1.27)
				)
				(justify left)
			)
		)
		(property "Value" "TP_0.75mm_SMD"
			(at 345.44 36.83 0)
			(effects
				(font
					(size 1.27 1.27)
					(thickness 0.15)
				)
				(justify left bottom)
				(hide yes)
			)
		)
		(property "Footprint" "antmicro-footprints:TP_SMD_0.75mm"
			(at 345.44 34.29 0)
			(effects
				(font
					(size 1.27 1.27)
					(thickness 0.15)
				)
				(justify left bottom)
				(hide yes)
			)
		)
		(property "Datasheet" ""
			(at 337.82 27.94 0)
			(effects
				(font
					(size 1.27 1.27)
					(thickness 0.15)
				)
				(justify left bottom)
				(hide yes)
			)
		)
		(property "Description" ""
			(at 355.6 40.64 0)
			(effects
				(font
					(size 1.27 1.27)
				)
				(hide yes)
			)
		)
		(property "MPN" ""
			(at 344.805 29.21 0)
			(effects
				(font
					(size 1.27 1.27)
					(thickness 0.15)
				)
				(justify left bottom)
				(hide yes)
			)
		)
		(property "Manufacturer" ""
			(at 344.805 34.29 0)
			(effects
				(font
					(size 1.27 1.27)
					(thickness 0.15)
				)
				(justify left bottom)
				(hide yes)
			)
		)
		(property "Author" "Antmicro"
			(at 345.44 31.75 0)
			(effects
				(font
					(size 1.27 1.27)
					(thickness 0.15)
				)
				(justify left bottom)
				(hide yes)
			)
		)
		(property "License" "Apache-2.0"
			(at 345.44 29.21 0)
			(effects
				(font
					(size 1.27 1.27)
					(thickness 0.15)
				)
				(justify left bottom)
				(hide yes)
			)
		)
		(pin "1"
		)
		(instances
			(project "jetson-orin-baseboard"
				(path ""
					(reference "TP17")
					(unit 1)
				)
			)
		)
	)
	(symbol
		(lib_id "antmicroResistors0402:R_200R_0402")
		(at 120.65 193.04 270)
		(mirror x)
		(unit 1)
		(exclude_from_sim no)
		(in_bom yes)
		(on_board yes)
		(dnp no)
		(property "Reference" "R72"
			(at 119.38 189.23 90)
			(effects
				(font
					(size 1.27 1.27)
				)
				(justify right)
			)
		)
		(property "Value" "R_200R_0402"
			(at 107.95 172.72 0)
			(effects
				(font
					(size 1.27 1.27)
					(thickness 0.15)
				)
				(justify left bottom)
				(hide yes)
			)
		)
		(property "Footprint" "antmicro-footprints:R_0402_1005Metric"
			(at 105.41 172.72 0)
			(effects
				(font
					(size 1.27 1.27)
					(thickness 0.15)
				)
				(justify left bottom)
				(hide yes)
			)
		)
		(property "Datasheet" "https://www.bourns.com/docs/product-datasheets/cr.pdf"
			(at 102.87 172.72 0)
			(effects
				(font
					(size 1.27 1.27)
					(thickness 0.15)
				)
				(justify left bottom)
				(hide yes)
			)
		)
		(property "Description" ""
			(at 120.65 193.04 0)
			(effects
				(font
					(size 1.27 1.27)
				)
				(hide yes)
			)
		)
		(property "Manufacturer" "Bourns"
			(at 97.79 172.72 0)
			(effects
				(font
					(size 1.27 1.27)
					(thickness 0.15)
				)
				(justify left bottom)
				(hide yes)
			)
		)
		(property "MPN" "CR0402-FX-2000GLF"
			(at 100.33 172.72 0)
			(effects
				(font
					(size 1.27 1.27)
					(thickness 0.15)
				)
				(justify left bottom)
				(hide yes)
			)
		)
		(property "Val" "200R"
			(at 119.38 191.77 90)
			(effects
				(font
					(size 1.27 1.27)
					(thickness 0.15)
				)
				(justify right)
			)
		)
		(property "License" "Apache-2.0"
			(at 95.25 172.72 0)
			(effects
				(font
					(size 1.27 1.27)
					(thickness 0.15)
				)
				(justify left bottom)
				(hide yes)
			)
		)
		(property "Author" "Antmicro"
			(at 92.71 172.72 0)
			(effects
				(font
					(size 1.27 1.27)
					(thickness 0.15)
				)
				(justify left bottom)
				(hide yes)
			)
		)
		(property "Tolerance" "1%"
			(at 110.49 172.72 0)
			(effects
				(font
					(size 1.27 1.27)
				)
				(justify left bottom)
				(hide yes)
			)
		)
		(pin "1"
		)
		(pin "2"
		)
		(instances
			(project "jetson-orin-baseboard"
				(path ""
					(reference "R72")
					(unit 1)
				)
			)
		)
	)
	(symbol
		(lib_id "antmicroResistors0402:R_10k_0402")
		(at 252.73 40.64 90)
		(unit 1)
		(exclude_from_sim no)
		(in_bom yes)
		(on_board yes)
		(dnp no)
		(property "Reference" "R83"
			(at 254 36.83 90)
			(effects
				(font
					(size 1.27 1.27)
				)
				(justify right)
			)
		)
		(property "Value" "R_10k_0402"
			(at 265.43 20.32 0)
			(effects
				(font
					(size 1.27 1.27)
					(thickness 0.15)
				)
				(justify left bottom)
				(hide yes)
			)
		)
		(property "Footprint" "antmicro-footprints:R_0402_1005Metric"
			(at 267.97 20.32 0)
			(effects
				(font
					(size 1.27 1.27)
					(thickness 0.15)
				)
				(justify left bottom)
				(hide yes)
			)
		)
		(property "Datasheet" "https://www.bourns.com/docs/product-datasheets/cr.pdf"
			(at 270.51 20.32 0)
			(effects
				(font
					(size 1.27 1.27)
					(thickness 0.15)
				)
				(justify left bottom)
				(hide yes)
			)
		)
		(property "Description" ""
			(at 252.73 40.64 0)
			(effects
				(font
					(size 1.27 1.27)
				)
				(hide yes)
			)
		)
		(property "Manufacturer" "Bourns"
			(at 275.59 20.32 0)
			(effects
				(font
					(size 1.27 1.27)
					(thickness 0.15)
				)
				(justify left bottom)
				(hide yes)
			)
		)
		(property "MPN" "CR0402-FX-1002GLF"
			(at 273.05 20.32 0)
			(effects
				(font
					(size 1.27 1.27)
					(thickness 0.15)
				)
				(justify left bottom)
				(hide yes)
			)
		)
		(property "Val" "10k"
			(at 254 39.37 90)
			(effects
				(font
					(size 1.27 1.27)
					(thickness 0.15)
				)
				(justify right)
			)
		)
		(property "License" "Apache-2.0"
			(at 278.13 20.32 0)
			(effects
				(font
					(size 1.27 1.27)
					(thickness 0.15)
				)
				(justify left bottom)
				(hide yes)
			)
		)
		(property "Author" "Antmicro"
			(at 280.67 20.32 0)
			(effects
				(font
					(size 1.27 1.27)
					(thickness 0.15)
				)
				(justify left bottom)
				(hide yes)
			)
		)
		(property "Tolerance" "1%"
			(at 262.89 20.32 0)
			(effects
				(font
					(size 1.27 1.27)
				)
				(justify left bottom)
				(hide yes)
			)
		)
		(pin "1"
		)
		(pin "2"
		)
		(instances
			(project "jetson-orin-baseboard"
				(path ""
					(reference "R83")
					(unit 1)
				)
			)
		)
	)
	(symbol
		(lib_id "antmicroResistors0402:R_10k_0402")
		(at 288.29 59.69 90)
		(unit 1)
		(exclude_from_sim no)
		(in_bom yes)
		(on_board yes)
		(dnp no)
		(property "Reference" "R99"
			(at 289.56 55.88 90)
			(effects
				(font
					(size 1.27 1.27)
				)
				(justify right)
			)
		)
		(property "Value" "R_10k_0402"
			(at 300.99 39.37 0)
			(effects
				(font
					(size 1.27 1.27)
					(thickness 0.15)
				)
				(justify left bottom)
				(hide yes)
			)
		)
		(property "Footprint" "antmicro-footprints:R_0402_1005Metric"
			(at 303.53 39.37 0)
			(effects
				(font
					(size 1.27 1.27)
					(thickness 0.15)
				)
				(justify left bottom)
				(hide yes)
			)
		)
		(property "Datasheet" "https://www.bourns.com/docs/product-datasheets/cr.pdf"
			(at 306.07 39.37 0)
			(effects
				(font
					(size 1.27 1.27)
					(thickness 0.15)
				)
				(justify left bottom)
				(hide yes)
			)
		)
		(property "Description" ""
			(at 288.29 59.69 0)
			(effects
				(font
					(size 1.27 1.27)
				)
				(hide yes)
			)
		)
		(property "Manufacturer" "Bourns"
			(at 311.15 39.37 0)
			(effects
				(font
					(size 1.27 1.27)
					(thickness 0.15)
				)
				(justify left bottom)
				(hide yes)
			)
		)
		(property "MPN" "CR0402-FX-1002GLF"
			(at 308.61 39.37 0)
			(effects
				(font
					(size 1.27 1.27)
					(thickness 0.15)
				)
				(justify left bottom)
				(hide yes)
			)
		)
		(property "Val" "10k"
			(at 289.56 58.42 90)
			(effects
				(font
					(size 1.27 1.27)
					(thickness 0.15)
				)
				(justify right)
			)
		)
		(property "License" "Apache-2.0"
			(at 313.69 39.37 0)
			(effects
				(font
					(size 1.27 1.27)
					(thickness 0.15)
				)
				(justify left bottom)
				(hide yes)
			)
		)
		(property "Author" "Antmicro"
			(at 316.23 39.37 0)
			(effects
				(font
					(size 1.27 1.27)
					(thickness 0.15)
				)
				(justify left bottom)
				(hide yes)
			)
		)
		(property "Tolerance" "1%"
			(at 298.45 39.37 0)
			(effects
				(font
					(size 1.27 1.27)
				)
				(justify left bottom)
				(hide yes)
			)
		)
		(pin "1"
		)
		(pin "2"
		)
		(instances
			(project "jetson-orin-baseboard"
				(path ""
					(reference "R99")
					(unit 1)
				)
			)
		)
	)
	(symbol
		(lib_name "GND_3")
		(lib_id "antmicropower:GND")
		(at 193.04 267.97 0)
		(mirror y)
		(unit 1)
		(exclude_from_sim no)
		(in_bom yes)
		(on_board yes)
		(dnp no)
		(property "Reference" "#PWR087"
			(at 193.04 274.32 0)
			(effects
				(font
					(size 1.27 1.27)
				)
				(justify left bottom)
				(hide yes)
			)
		)
		(property "Value" "GND"
			(at 193.04 271.78 0)
			(effects
				(font
					(size 1.27 1.27)
					(thickness 0.15)
				)
			)
		)
		(property "Footprint" ""
			(at 184.15 275.59 0)
			(effects
				(font
					(size 1.27 1.27)
					(thickness 0.15)
				)
				(justify left bottom)
				(hide yes)
			)
		)
		(property "Datasheet" ""
			(at 184.15 280.67 0)
			(effects
				(font
					(size 1.27 1.27)
					(thickness 0.15)
				)
				(justify left bottom)
				(hide yes)
			)
		)
		(property "Description" ""
			(at 193.04 267.97 0)
			(effects
				(font
					(size 1.27 1.27)
				)
				(hide yes)
			)
		)
		(property "Author" "Antmicro"
			(at 184.15 275.59 0)
			(effects
				(font
					(size 1.27 1.27)
					(thickness 0.15)
				)
				(justify left bottom)
				(hide yes)
			)
		)
		(property "License" "Apache-2.0"
			(at 184.15 278.13 0)
			(effects
				(font
					(size 1.27 1.27)
					(thickness 0.15)
				)
				(justify left bottom)
				(hide yes)
			)
		)
		(pin "1"
		)
		(instances
			(project "jetson-orin-baseboard"
				(path ""
					(reference "#PWR087")
					(unit 1)
				)
			)
		)
	)
	(symbol
		(lib_id "antmicroCapacitors0402:C_100n_0402")
		(at 181.61 121.92 0)
		(mirror x)
		(unit 1)
		(exclude_from_sim no)
		(in_bom yes)
		(on_board yes)
		(dnp no)
		(property "Reference" "C144"
			(at 187.96 120.65 0)
			(effects
				(font
					(size 1.27 1.27)
				)
			)
		)
		(property "Value" "C_100n_0402"
			(at 201.93 111.76 0)
			(effects
				(font
					(size 1.27 1.27)
					(thickness 0.15)
				)
				(justify left bottom)
				(hide yes)
			)
		)
		(property "Footprint" "antmicro-footprints:C_0402_1005Metric"
			(at 201.93 109.22 0)
			(effects
				(font
					(size 1.27 1.27)
					(thickness 0.15)
				)
				(justify left bottom)
				(hide yes)
			)
		)
		(property "Datasheet" "https://www.murata.com/products/productdetail?partno=GRM155R61H104KE14%23"
			(at 201.93 106.68 0)
			(effects
				(font
					(size 1.27 1.27)
					(thickness 0.15)
				)
				(justify left bottom)
				(hide yes)
			)
		)
		(property "Description" ""
			(at 181.61 121.92 0)
			(effects
				(font
					(size 1.27 1.27)
				)
				(hide yes)
			)
		)
		(property "Manufacturer" "Murata"
			(at 201.93 101.6 0)
			(effects
				(font
					(size 1.27 1.27)
					(thickness 0.15)
				)
				(justify left bottom)
				(hide yes)
			)
		)
		(property "MPN" "GRM155R61H104KE14D"
			(at 201.93 104.14 0)
			(effects
				(font
					(size 1.27 1.27)
					(thickness 0.15)
				)
				(justify left bottom)
				(hide yes)
			)
		)
		(property "Val" "100n"
			(at 180.34 123.19 0)
			(effects
				(font
					(size 1.27 1.27)
					(thickness 0.15)
				)
			)
		)
		(property "License" "Apache-2.0"
			(at 201.93 99.06 0)
			(effects
				(font
					(size 1.27 1.27)
					(thickness 0.15)
				)
				(justify left bottom)
				(hide yes)
			)
		)
		(property "Author" "Antmicro"
			(at 201.93 96.52 0)
			(effects
				(font
					(size 1.27 1.27)
					(thickness 0.15)
				)
				(justify left bottom)
				(hide yes)
			)
		)
		(property "Voltage" "50V"
			(at 201.93 93.98 0)
			(effects
				(font
					(size 1.27 1.27)
				)
				(justify left bottom)
				(hide yes)
			)
		)
		(property "Dielectric" "X5R"
			(at 201.93 91.44 0)
			(effects
				(font
					(size 1.27 1.27)
				)
				(justify left bottom)
				(hide yes)
			)
		)
		(pin "1"
		)
		(pin "2"
		)
		(instances
			(project "jetson-orin-baseboard"
				(path ""
					(reference "C144")
					(unit 1)
				)
			)
		)
	)
	(symbol
		(lib_name "GND_3")
		(lib_id "antmicropower:GND")
		(at 307.34 137.16 0)
		(mirror y)
		(unit 1)
		(exclude_from_sim no)
		(in_bom yes)
		(on_board yes)
		(dnp no)
		(property "Reference" "#PWR096"
			(at 307.34 143.51 0)
			(effects
				(font
					(size 1.27 1.27)
				)
				(justify left bottom)
				(hide yes)
			)
		)
		(property "Value" "GND"
			(at 307.34 140.97 0)
			(effects
				(font
					(size 1.27 1.27)
					(thickness 0.15)
				)
			)
		)
		(property "Footprint" ""
			(at 298.45 144.78 0)
			(effects
				(font
					(size 1.27 1.27)
					(thickness 0.15)
				)
				(justify left bottom)
				(hide yes)
			)
		)
		(property "Datasheet" ""
			(at 298.45 149.86 0)
			(effects
				(font
					(size 1.27 1.27)
					(thickness 0.15)
				)
				(justify left bottom)
				(hide yes)
			)
		)
		(property "Description" ""
			(at 307.34 137.16 0)
			(effects
				(font
					(size 1.27 1.27)
				)
				(hide yes)
			)
		)
		(property "Author" "Antmicro"
			(at 298.45 144.78 0)
			(effects
				(font
					(size 1.27 1.27)
					(thickness 0.15)
				)
				(justify left bottom)
				(hide yes)
			)
		)
		(property "License" "Apache-2.0"
			(at 298.45 147.32 0)
			(effects
				(font
					(size 1.27 1.27)
					(thickness 0.15)
				)
				(justify left bottom)
				(hide yes)
			)
		)
		(pin "1"
		)
		(instances
			(project "jetson-orin-baseboard"
				(path ""
					(reference "#PWR096")
					(unit 1)
				)
			)
		)
	)
	(symbol
		(lib_id "antmicroPMICVoltageRegulatorsLinear:NCP730BMT330_WSON")
		(at 41.91 172.72 0)
		(unit 1)
		(exclude_from_sim no)
		(in_bom yes)
		(on_board yes)
		(dnp no)
		(fields_autoplaced yes)
		(property "Reference" "U8"
			(at 49.53 165.1 0)
			(effects
				(font
					(size 1.27 1.27)
				)
			)
		)
		(property "Value" "NCP730BMT330_WSON"
			(at 72.39 177.8 0)
			(effects
				(font
					(size 1.27 1.27)
					(thickness 0.15)
				)
				(justify left bottom)
				(hide yes)
			)
		)
		(property "Footprint" "antmicro-footprints:WSON-6-1EP_2x2mm_P0.65mm"
			(at 72.39 180.34 0)
			(effects
				(font
					(size 1.27 1.27)
					(thickness 0.15)
				)
				(justify left bottom)
				(hide yes)
			)
		)
		(property "Datasheet" "https://www.onsemi.com/download/data-sheet/pdf/ncp730-d.pdf"
			(at 72.39 182.88 0)
			(effects
				(font
					(size 1.27 1.27)
					(thickness 0.15)
				)
				(justify left bottom)
				(hide yes)
			)
		)
		(property "Description" ""
			(at 41.91 172.72 0)
			(effects
				(font
					(size 1.27 1.27)
				)
				(hide yes)
			)
		)
		(property "MPN" "NCP730BMT330TBG"
			(at 49.53 167.64 0)
			(effects
				(font
					(size 1.27 1.27)
					(thickness 0.15)
				)
			)
		)
		(property "Manufacturer" "ON Semiconductor"
			(at 72.39 187.96 0)
			(effects
				(font
					(size 1.27 1.27)
					(thickness 0.15)
				)
				(justify left bottom)
				(hide yes)
			)
		)
		(property "Author" "Antmicro"
			(at 72.39 190.5 0)
			(effects
				(font
					(size 1.27 1.27)
					(thickness 0.15)
				)
				(justify left bottom)
				(hide yes)
			)
		)
		(property "License" "Apache-2.0"
			(at 72.39 193.04 0)
			(effects
				(font
					(size 1.27 1.27)
					(thickness 0.15)
				)
				(justify left bottom)
				(hide yes)
			)
		)
		(pin "1"
		)
		(pin "2"
		)
		(pin "3"
		)
		(pin "4"
		)
		(pin "5"
		)
		(pin "6"
		)
		(pin "7"
		)
		(instances
			(project "jetson-orin-baseboard"
				(path ""
					(reference "U8")
					(unit 1)
				)
			)
		)
	)
	(symbol
		(lib_id "antmicroCapacitors0402:C_10u_0402")
		(at 27.94 45.72 90)
		(unit 1)
		(exclude_from_sim no)
		(in_bom yes)
		(on_board yes)
		(dnp no)
		(property "Reference" "C28"
			(at 28.575 41.275 90)
			(effects
				(font
					(size 1.27 1.27)
					(thickness 0.15)
				)
				(justify right)
			)
		)
		(property "Value" "C_10u_0402"
			(at 38.1 25.4 0)
			(effects
				(font
					(size 1.27 1.27)
					(thickness 0.15)
				)
				(justify left bottom)
				(hide yes)
			)
		)
		(property "Footprint" "antmicro-footprints:C_0402_1005Metric"
			(at 40.64 25.4 0)
			(effects
				(font
					(size 1.27 1.27)
					(thickness 0.15)
				)
				(justify left bottom)
				(hide yes)
			)
		)
		(property "Datasheet" "https://www.yageo.com/en/Chart/Download/pdf/CC0402MRX5R5BB106"
			(at 43.18 25.4 0)
			(effects
				(font
					(size 1.27 1.27)
					(thickness 0.15)
				)
				(justify left bottom)
				(hide yes)
			)
		)
		(property "Description" ""
			(at 27.94 45.72 0)
			(effects
				(font
					(size 1.27 1.27)
				)
				(hide yes)
			)
		)
		(property "MPN" "CC0402MRX5R5BB106"
			(at 45.72 25.4 0)
			(effects
				(font
					(size 1.27 1.27)
					(thickness 0.15)
				)
				(justify left bottom)
				(hide yes)
			)
		)
		(property "Manufacturer" "YAGEO"
			(at 48.26 25.4 0)
			(effects
				(font
					(size 1.27 1.27)
					(thickness 0.15)
				)
				(justify left bottom)
				(hide yes)
			)
		)
		(property "License" "Apache-2.0"
			(at 50.8 25.4 0)
			(effects
				(font
					(size 1.27 1.27)
					(thickness 0.15)
				)
				(justify left bottom)
				(hide yes)
			)
		)
		(property "Author" "Antmicro"
			(at 53.34 25.4 0)
			(effects
				(font
					(size 1.27 1.27)
					(thickness 0.15)
				)
				(justify left bottom)
				(hide yes)
			)
		)
		(property "Val" "10u"
			(at 28.575 45.085 90)
			(effects
				(font
					(size 1.27 1.27)
					(thickness 0.15)
				)
				(justify right)
			)
		)
		(property "Voltage" ""
			(at 55.88 25.4 0)
			(effects
				(font
					(size 1.27 1.27)
				)
				(justify left bottom)
				(hide yes)
			)
		)
		(property "Dielectric" ""
			(at 58.42 25.4 0)
			(effects
				(font
					(size 1.27 1.27)
				)
				(justify left bottom)
				(hide yes)
			)
		)
		(pin "1"
		)
		(pin "2"
		)
		(instances
			(project "jetson-orin-baseboard"
				(path ""
					(reference "C28")
					(unit 1)
				)
			)
		)
	)
	(symbol
		(lib_name "GND_3")
		(lib_id "antmicropower:GND")
		(at 25.4 68.58 0)
		(mirror y)
		(unit 1)
		(exclude_from_sim no)
		(in_bom yes)
		(on_board yes)
		(dnp no)
		(property "Reference" "#PWR051"
			(at 25.4 74.93 0)
			(effects
				(font
					(size 1.27 1.27)
				)
				(justify left bottom)
				(hide yes)
			)
		)
		(property "Value" "GND"
			(at 25.4 72.39 0)
			(effects
				(font
					(size 1.27 1.27)
					(thickness 0.15)
				)
			)
		)
		(property "Footprint" ""
			(at 16.51 76.2 0)
			(effects
				(font
					(size 1.27 1.27)
					(thickness 0.15)
				)
				(justify left bottom)
				(hide yes)
			)
		)
		(property "Datasheet" ""
			(at 16.51 81.28 0)
			(effects
				(font
					(size 1.27 1.27)
					(thickness 0.15)
				)
				(justify left bottom)
				(hide yes)
			)
		)
		(property "Description" ""
			(at 25.4 68.58 0)
			(effects
				(font
					(size 1.27 1.27)
				)
				(hide yes)
			)
		)
		(property "Author" "Antmicro"
			(at 16.51 76.2 0)
			(effects
				(font
					(size 1.27 1.27)
					(thickness 0.15)
				)
				(justify left bottom)
				(hide yes)
			)
		)
		(property "License" "Apache-2.0"
			(at 16.51 78.74 0)
			(effects
				(font
					(size 1.27 1.27)
					(thickness 0.15)
				)
				(justify left bottom)
				(hide yes)
			)
		)
		(pin "1"
		)
		(instances
			(project "jetson-orin-baseboard"
				(path ""
					(reference "#PWR051")
					(unit 1)
				)
			)
		)
	)
	(symbol
		(lib_id "antmicroResistors0402:R_100k_0402")
		(at 39.37 241.3 90)
		(unit 1)
		(exclude_from_sim no)
		(in_bom yes)
		(on_board yes)
		(dnp no)
		(fields_autoplaced yes)
		(property "Reference" "R270"
			(at 41.91 237.49 90)
			(effects
				(font
					(size 1.27 1.27)
					(thickness 0.15)
				)
				(justify right)
			)
		)
		(property "Value" "R_100k_0402"
			(at 52.07 220.98 0)
			(effects
				(font
					(size 1.27 1.27)
					(thickness 0.15)
				)
				(justify left bottom)
				(hide yes)
			)
		)
		(property "Footprint" "antmicro-footprints:R_0402_1005Metric"
			(at 54.61 220.98 0)
			(effects
				(font
					(size 1.27 1.27)
					(thickness 0.15)
				)
				(justify left bottom)
				(hide yes)
			)
		)
		(property "Datasheet" "https://www.bourns.com/docs/product-datasheets/cr.pdf"
			(at 57.15 220.98 0)
			(effects
				(font
					(size 1.27 1.27)
					(thickness 0.15)
				)
				(justify left bottom)
				(hide yes)
			)
		)
		(property "Description" ""
			(at 39.37 241.3 0)
			(effects
				(font
					(size 1.27 1.27)
				)
				(hide yes)
			)
		)
		(property "MPN" "CR0402-FX-1003GLF"
			(at 59.69 220.98 0)
			(effects
				(font
					(size 1.27 1.27)
					(thickness 0.15)
				)
				(justify left bottom)
				(hide yes)
			)
		)
		(property "Manufacturer" "Bourns"
			(at 62.23 220.98 0)
			(effects
				(font
					(size 1.27 1.27)
					(thickness 0.15)
				)
				(justify left bottom)
				(hide yes)
			)
		)
		(property "License" "Apache-2.0"
			(at 64.77 220.98 0)
			(effects
				(font
					(size 1.27 1.27)
					(thickness 0.15)
				)
				(justify left bottom)
				(hide yes)
			)
		)
		(property "Author" "Antmicro"
			(at 67.31 220.98 0)
			(effects
				(font
					(size 1.27 1.27)
					(thickness 0.15)
				)
				(justify left bottom)
				(hide yes)
			)
		)
		(property "Val" "100k"
			(at 41.91 240.03 90)
			(effects
				(font
					(size 1.27 1.27)
					(thickness 0.15)
				)
				(justify right)
			)
		)
		(property "Tolerance" "1%"
			(at 49.53 220.98 0)
			(effects
				(font
					(size 1.27 1.27)
				)
				(justify left bottom)
				(hide yes)
			)
		)
		(pin "2"
		)
		(pin "1"
		)
		(instances
			(project "jetson-orin-baseboard"
				(path ""
					(reference "R270")
					(unit 1)
				)
			)
		)
	)
	(symbol
		(lib_id "antmicroResistors0402:R_0R_0402")
		(at 204.47 95.25 90)
		(unit 1)
		(exclude_from_sim no)
		(in_bom no)
		(on_board yes)
		(dnp yes)
		(property "Reference" "R82"
			(at 206.375 91.44 90)
			(effects
				(font
					(size 1.27 1.27)
				)
				(justify right)
			)
		)
		(property "Value" "R_0R_0402"
			(at 217.17 74.93 0)
			(effects
				(font
					(size 1.27 1.27)
					(thickness 0.15)
				)
				(justify left bottom)
				(hide yes)
			)
		)
		(property "Footprint" "antmicro-footprints:R_0402_1005Metric"
			(at 219.71 74.93 0)
			(effects
				(font
					(size 1.27 1.27)
					(thickness 0.15)
				)
				(justify left bottom)
				(hide yes)
			)
		)
		(property "Datasheet" "https://industrial.panasonic.com/cdbs/www-data/pdf/RDA0000/AOA0000C301.pdf"
			(at 222.25 74.93 0)
			(effects
				(font
					(size 1.27 1.27)
					(thickness 0.15)
				)
				(justify left bottom)
				(hide yes)
			)
		)
		(property "Description" ""
			(at 204.47 95.25 0)
			(effects
				(font
					(size 1.27 1.27)
				)
				(hide yes)
			)
		)
		(property "Manufacturer" "Panasonic"
			(at 227.33 74.93 0)
			(effects
				(font
					(size 1.27 1.27)
					(thickness 0.15)
				)
				(justify left bottom)
				(hide yes)
			)
		)
		(property "MPN" "ERJ2GE0R00X"
			(at 224.79 74.93 0)
			(effects
				(font
					(size 1.27 1.27)
					(thickness 0.15)
				)
				(justify left bottom)
				(hide yes)
			)
		)
		(property "Val" "0R"
			(at 206.375 93.98 90)
			(effects
				(font
					(size 1.27 1.27)
					(thickness 0.15)
				)
				(justify right)
			)
		)
		(property "License" "Apache-2.0"
			(at 229.87 74.93 0)
			(effects
				(font
					(size 1.27 1.27)
					(thickness 0.15)
				)
				(justify left bottom)
				(hide yes)
			)
		)
		(property "Author" "Antmicro"
			(at 232.41 74.93 0)
			(effects
				(font
					(size 1.27 1.27)
					(thickness 0.15)
				)
				(justify left bottom)
				(hide yes)
			)
		)
		(property "Tolerance" "~"
			(at 214.63 74.93 0)
			(effects
				(font
					(size 1.27 1.27)
				)
				(justify left bottom)
				(hide yes)
			)
		)
		(property "Current" "1A"
			(at 234.95 74.93 0)
			(effects
				(font
					(size 1.27 1.27)
					(thickness 0.15)
				)
				(justify left bottom)
				(hide yes)
			)
		)
		(pin "1"
		)
		(pin "2"
		)
		(instances
			(project "jetson-orin-baseboard"
				(path ""
					(reference "R82")
					(unit 1)
				)
			)
		)
	)
	(symbol
		(lib_name "AP22615A_TSOT26_1")
		(lib_id "antmicroPMICPowerDistributionSwitchesLoadDrivers:AP22615A_TSOT26")
		(at 210.82 207.01 0)
		(unit 1)
		(exclude_from_sim no)
		(in_bom yes)
		(on_board yes)
		(dnp no)
		(property "Reference" "U9"
			(at 218.44 200.66 0)
			(effects
				(font
					(size 1.27 1.27)
				)
			)
		)
		(property "Value" "AP22615A_TSOT26"
			(at 241.3 212.09 0)
			(effects
				(font
					(size 1.27 1.27)
					(thickness 0.15)
				)
				(justify left bottom)
				(hide yes)
			)
		)
		(property "Footprint" "antmicro-footprints:TSOT23-6"
			(at 241.3 214.63 0)
			(effects
				(font
					(size 1.27 1.27)
					(thickness 0.15)
				)
				(justify left bottom)
				(hide yes)
			)
		)
		(property "Datasheet" "https://www.mouser.com/datasheet/2/115/DIOD_S_A0008958405_1-2543193.pdf"
			(at 241.3 217.17 0)
			(effects
				(font
					(size 1.27 1.27)
					(thickness 0.15)
				)
				(justify left bottom)
				(hide yes)
			)
		)
		(property "Description" ""
			(at 210.82 207.01 0)
			(effects
				(font
					(size 1.27 1.27)
				)
				(hide yes)
			)
		)
		(property "MPN" "AP22615AWU-7"
			(at 218.44 203.2 0)
			(effects
				(font
					(size 1.27 1.27)
					(thickness 0.15)
				)
			)
		)
		(property "Manufacturer" "Diodes Incorporated"
			(at 241.3 222.25 0)
			(effects
				(font
					(size 1.27 1.27)
					(thickness 0.15)
				)
				(justify left bottom)
				(hide yes)
			)
		)
		(property "Author" "Antmicro"
			(at 241.3 224.79 0)
			(effects
				(font
					(size 1.27 1.27)
					(thickness 0.15)
				)
				(justify left bottom)
				(hide yes)
			)
		)
		(property "License" "Apache-2.0"
			(at 241.3 227.33 0)
			(effects
				(font
					(size 1.27 1.27)
					(thickness 0.15)
				)
				(justify left bottom)
				(hide yes)
			)
		)
		(pin "1"
		)
		(pin "2"
		)
		(pin "3"
		)
		(pin "4"
		)
		(pin "5"
		)
		(pin "6"
		)
		(instances
			(project "jetson-orin-baseboard"
				(path ""
					(reference "U9")
					(unit 1)
				)
			)
		)
	)
	(symbol
		(lib_id "antmicroTVSDiodes:TPD4E05U06QDQARQ1")
		(at 350.52 64.77 270)
		(mirror x)
		(unit 1)
		(exclude_from_sim no)
		(in_bom yes)
		(on_board yes)
		(dnp no)
		(property "Reference" "U16"
			(at 346.075 52.07 90)
			(effects
				(font
					(size 1.27 1.27)
				)
			)
		)
		(property "Value" "TPD4E05U06QDQARQ1"
			(at 340.36 40.64 0)
			(effects
				(font
					(size 1.27 1.27)
					(thickness 0.15)
				)
				(justify left bottom)
				(hide yes)
			)
		)
		(property "Footprint" "antmicro-footprints:USON-10_2.5x1mm_P0.5mm"
			(at 345.44 40.64 0)
			(effects
				(font
					(size 1.27 1.27)
					(thickness 0.15)
				)
				(justify left bottom)
				(hide yes)
			)
		)
		(property "Datasheet" "https://www.ti.com/lit/ds/symlink/tpd4e05u06-q1.pdf?HQS=dis-mous-null-mousermode-dsf-pf-null-wwe&ts=1663591265741&ref_url=https%253A%252F%252Fwww.mouser.com%252F"
			(at 342.9 40.64 0)
			(effects
				(font
					(size 1.27 1.27)
					(thickness 0.15)
				)
				(justify left bottom)
				(hide yes)
			)
		)
		(property "Description" ""
			(at 350.52 64.77 0)
			(effects
				(font
					(size 1.27 1.27)
				)
				(hide yes)
			)
		)
		(property "Manufacturer" "Texas Instruments"
			(at 337.82 40.64 0)
			(effects
				(font
					(size 1.27 1.27)
					(thickness 0.15)
				)
				(justify left bottom)
				(hide yes)
			)
		)
		(property "MPN" "TPD4E05U06QDQARQ1"
			(at 346.075 54.61 90)
			(effects
				(font
					(size 1.27 1.27)
					(thickness 0.15)
				)
			)
		)
		(property "Author" "Antmicro"
			(at 335.28 40.64 0)
			(effects
				(font
					(size 1.27 1.27)
					(thickness 0.15)
				)
				(justify left bottom)
				(hide yes)
			)
		)
		(property "License" "Apache-2.0"
			(at 332.74 40.64 0)
			(effects
				(font
					(size 1.27 1.27)
					(thickness 0.15)
				)
				(justify left bottom)
				(hide yes)
			)
		)
		(pin "1"
		)
		(pin "10"
		)
		(pin "2"
		)
		(pin "3"
		)
		(pin "4"
		)
		(pin "5"
		)
		(pin "6"
		)
		(pin "7"
		)
		(pin "8"
		)
		(pin "9"
		)
		(instances
			(project "jetson-orin-baseboard"
				(path ""
					(reference "U16")
					(unit 1)
				)
			)
		)
	)
	(symbol
		(lib_name "GND_3")
		(lib_id "antmicropower:GND")
		(at 25.4 80.01 0)
		(mirror y)
		(unit 1)
		(exclude_from_sim no)
		(in_bom yes)
		(on_board yes)
		(dnp no)
		(property "Reference" "#PWR052"
			(at 25.4 86.36 0)
			(effects
				(font
					(size 1.27 1.27)
				)
				(justify left bottom)
				(hide yes)
			)
		)
		(property "Value" "GND"
			(at 25.4 83.82 0)
			(effects
				(font
					(size 1.27 1.27)
					(thickness 0.15)
				)
			)
		)
		(property "Footprint" ""
			(at 16.51 87.63 0)
			(effects
				(font
					(size 1.27 1.27)
					(thickness 0.15)
				)
				(justify left bottom)
				(hide yes)
			)
		)
		(property "Datasheet" ""
			(at 16.51 92.71 0)
			(effects
				(font
					(size 1.27 1.27)
					(thickness 0.15)
				)
				(justify left bottom)
				(hide yes)
			)
		)
		(property "Description" ""
			(at 25.4 80.01 0)
			(effects
				(font
					(size 1.27 1.27)
				)
				(hide yes)
			)
		)
		(property "Author" "Antmicro"
			(at 16.51 87.63 0)
			(effects
				(font
					(size 1.27 1.27)
					(thickness 0.15)
				)
				(justify left bottom)
				(hide yes)
			)
		)
		(property "License" "Apache-2.0"
			(at 16.51 90.17 0)
			(effects
				(font
					(size 1.27 1.27)
					(thickness 0.15)
				)
				(justify left bottom)
				(hide yes)
			)
		)
		(pin "1"
		)
		(instances
			(project "jetson-orin-baseboard"
				(path ""
					(reference "#PWR052")
					(unit 1)
				)
			)
		)
	)
	(symbol
		(lib_id "antmicroInterfaceControllers:TPS65988DHRSHR")
		(at 323.85 73.66 0)
		(mirror y)
		(unit 3)
		(exclude_from_sim no)
		(in_bom yes)
		(on_board yes)
		(dnp no)
		(fields_autoplaced yes)
		(property "Reference" "U6"
			(at 307.975 66.04 0)
			(effects
				(font
					(size 1.27 1.27)
				)
			)
		)
		(property "Value" "TPS65988DHRSHR"
			(at 274.32 78.74 0)
			(effects
				(font
					(size 1.27 1.27)
					(thickness 0.15)
				)
				(justify left bottom)
				(hide yes)
			)
		)
		(property "Footprint" "antmicro-footprints:IC_TPS65987DDHRSHR"
			(at 274.32 81.28 0)
			(effects
				(font
					(size 1.27 1.27)
					(thickness 0.15)
				)
				(justify left bottom)
				(hide yes)
			)
		)
		(property "Datasheet" "https://www.ti.com/lit/ds/symlink/tps65988.pdf?ts=1662726631004&ref_url=https%253A%252F%252Fwww.ti.com%252Fproduct%252FTPS65988"
			(at 274.32 83.82 0)
			(effects
				(font
					(size 1.27 1.27)
					(thickness 0.15)
				)
				(justify left bottom)
				(hide yes)
			)
		)
		(property "Description" ""
			(at 323.85 73.66 0)
			(effects
				(font
					(size 1.27 1.27)
				)
				(hide yes)
			)
		)
		(property "MPN" "TPS65988DHRSHR "
			(at 307.975 68.58 0)
			(effects
				(font
					(size 1.27 1.27)
					(thickness 0.15)
				)
			)
		)
		(property "Manufacturer" "Texas Instruments"
			(at 274.32 88.9 0)
			(effects
				(font
					(size 1.27 1.27)
					(thickness 0.15)
				)
				(justify left bottom)
				(hide yes)
			)
		)
		(property "License" "Apache-2.0"
			(at 274.32 91.44 0)
			(effects
				(font
					(size 1.27 1.27)
					(thickness 0.15)
				)
				(justify left bottom)
				(hide yes)
			)
		)
		(property "Author" "Antmicro"
			(at 274.32 93.98 0)
			(effects
				(font
					(size 1.27 1.27)
					(thickness 0.15)
				)
				(justify left bottom)
				(hide yes)
			)
		)
		(pin "10"
		)
		(pin "16"
		)
		(pin "17"
		)
		(pin "18"
		)
		(pin "20"
		)
		(pin "21"
		)
		(pin "22"
		)
		(pin "23"
		)
		(pin "27"
		)
		(pin "28"
		)
		(pin "29"
		)
		(pin "30"
		)
		(pin "31"
		)
		(pin "32"
		)
		(pin "33"
		)
		(pin "34"
		)
		(pin "35"
		)
		(pin "36"
		)
		(pin "37"
		)
		(pin "38"
		)
		(pin "39"
		)
		(pin "40"
		)
		(pin "41"
		)
		(pin "42"
		)
		(pin "43"
		)
		(pin "44"
		)
		(pin "48"
		)
		(pin "49"
		)
		(pin "5"
		)
		(pin "51"
		)
		(pin "59"
		)
		(pin "6"
		)
		(pin "9"
		)
		(pin "11"
		)
		(pin "13"
		)
		(pin "15"
		)
		(pin "19"
		)
		(pin "24"
		)
		(pin "25"
		)
		(pin "26"
		)
		(pin "50"
		)
		(pin "53"
		)
		(pin "58"
		)
		(pin "8"
		)
		(pin "1"
		)
		(pin "3"
		)
		(pin "45"
		)
		(pin "46"
		)
		(pin "47"
		)
		(pin "52"
		)
		(pin "54"
		)
		(pin "55"
		)
		(pin "56"
		)
		(pin "57"
		)
		(pin "7"
		)
		(instances
			(project "jetson-orin-baseboard"
				(path ""
					(reference "U6")
					(unit 3)
				)
			)
		)
	)
	(symbol
		(lib_id "antmicroInterfaceControllers:TUSB1046-DCIRNQ")
		(at 210.82 99.06 0)
		(unit 1)
		(exclude_from_sim no)
		(in_bom yes)
		(on_board yes)
		(dnp no)
		(property "Reference" "U10"
			(at 223.52 92.71 0)
			(effects
				(font
					(size 1.27 1.27)
				)
			)
		)
		(property "Value" "TUSB1046-DCIRNQ"
			(at 248.92 104.14 0)
			(effects
				(font
					(size 1.27 1.27)
					(thickness 0.15)
				)
				(justify left bottom)
				(hide yes)
			)
		)
		(property "Footprint" "antmicro-footprints:WQFN-40_1EP_6x3mm_Pitch0.4mm_EP4.7x2.7mm"
			(at 248.92 106.68 0)
			(effects
				(font
					(size 1.27 1.27)
					(thickness 0.15)
				)
				(justify left bottom)
				(hide yes)
			)
		)
		(property "Datasheet" "https://www.ti.com/lit/ds/sllsew2d/sllsew2d.pdf?ts=1662107117482&ref_url=https%253A%252F%252Fwww.google.com%252F"
			(at 248.92 109.22 0)
			(effects
				(font
					(size 1.27 1.27)
					(thickness 0.15)
				)
				(justify left bottom)
				(hide yes)
			)
		)
		(property "Description" ""
			(at 210.82 99.06 0)
			(effects
				(font
					(size 1.27 1.27)
				)
				(hide yes)
			)
		)
		(property "MPN" "TUSB1046-DCIRNQT"
			(at 223.52 95.25 0)
			(effects
				(font
					(size 1.27 1.27)
					(thickness 0.15)
				)
			)
		)
		(property "Manufacturer" "Texas Instruments"
			(at 248.92 114.3 0)
			(effects
				(font
					(size 1.27 1.27)
					(thickness 0.15)
				)
				(justify left bottom)
				(hide yes)
			)
		)
		(property "Author" "Antmicro"
			(at 248.92 116.84 0)
			(effects
				(font
					(size 1.27 1.27)
					(thickness 0.15)
				)
				(justify left bottom)
				(hide yes)
			)
		)
		(property "License" "Apache-2.0"
			(at 248.92 119.38 0)
			(effects
				(font
					(size 1.27 1.27)
					(thickness 0.15)
				)
				(justify left bottom)
				(hide yes)
			)
		)
		(pin "1"
		)
		(pin "10"
		)
		(pin "11"
		)
		(pin "12"
		)
		(pin "13"
		)
		(pin "14"
		)
		(pin "15"
		)
		(pin "16"
		)
		(pin "17"
		)
		(pin "18"
		)
		(pin "19"
		)
		(pin "2"
		)
		(pin "20"
		)
		(pin "21"
		)
		(pin "22"
		)
		(pin "23"
		)
		(pin "24"
		)
		(pin "25"
		)
		(pin "26"
		)
		(pin "27"
		)
		(pin "28"
		)
		(pin "29"
		)
		(pin "3"
		)
		(pin "30"
		)
		(pin "31"
		)
		(pin "32"
		)
		(pin "33"
		)
		(pin "34"
		)
		(pin "35"
		)
		(pin "36"
		)
		(pin "37"
		)
		(pin "38"
		)
		(pin "39"
		)
		(pin "4"
		)
		(pin "40"
		)
		(pin "41"
		)
		(pin "5"
		)
		(pin "6"
		)
		(pin "7"
		)
		(pin "8"
		)
		(pin "9"
		)
		(instances
			(project "jetson-orin-baseboard"
				(path ""
					(reference "U10")
					(unit 1)
				)
			)
		)
	)
	(symbol
		(lib_name "GND_3")
		(lib_id "antmicropower:GND")
		(at 207.01 219.71 0)
		(mirror y)
		(unit 1)
		(exclude_from_sim no)
		(in_bom yes)
		(on_board yes)
		(dnp no)
		(property "Reference" "#PWR077"
			(at 207.01 226.06 0)
			(effects
				(font
					(size 1.27 1.27)
				)
				(justify left bottom)
				(hide yes)
			)
		)
		(property "Value" "GND"
			(at 207.01 223.52 0)
			(effects
				(font
					(size 1.27 1.27)
					(thickness 0.15)
				)
			)
		)
		(property "Footprint" ""
			(at 198.12 227.33 0)
			(effects
				(font
					(size 1.27 1.27)
					(thickness 0.15)
				)
				(justify left bottom)
				(hide yes)
			)
		)
		(property "Datasheet" ""
			(at 198.12 232.41 0)
			(effects
				(font
					(size 1.27 1.27)
					(thickness 0.15)
				)
				(justify left bottom)
				(hide yes)
			)
		)
		(property "Description" ""
			(at 207.01 219.71 0)
			(effects
				(font
					(size 1.27 1.27)
				)
				(hide yes)
			)
		)
		(property "Author" "Antmicro"
			(at 198.12 227.33 0)
			(effects
				(font
					(size 1.27 1.27)
					(thickness 0.15)
				)
				(justify left bottom)
				(hide yes)
			)
		)
		(property "License" "Apache-2.0"
			(at 198.12 229.87 0)
			(effects
				(font
					(size 1.27 1.27)
					(thickness 0.15)
				)
				(justify left bottom)
				(hide yes)
			)
		)
		(pin "1"
		)
		(instances
			(project "jetson-orin-baseboard"
				(path ""
					(reference "#PWR077")
					(unit 1)
				)
			)
		)
	)
	(symbol
		(lib_name "TP_0.75mm_SMD_3")
		(lib_id "antmicroTestPoints:TP_0.75mm_SMD")
		(at 173.99 172.72 180)
		(unit 1)
		(exclude_from_sim no)
		(in_bom no)
		(on_board yes)
		(dnp no)
		(property "Reference" "TP30"
			(at 170.18 172.72 0)
			(effects
				(font
					(size 1.27 1.27)
				)
				(justify left)
			)
		)
		(property "Value" "TP_0.75mm_SMD"
			(at 163.83 168.91 0)
			(effects
				(font
					(size 1.27 1.27)
					(thickness 0.15)
				)
				(justify left bottom)
				(hide yes)
			)
		)
		(property "Footprint" "antmicro-footprints:TP_SMD_0.75mm"
			(at 163.83 166.37 0)
			(effects
				(font
					(size 1.27 1.27)
					(thickness 0.15)
				)
				(justify left bottom)
				(hide yes)
			)
		)
		(property "Datasheet" ""
			(at 156.21 160.02 0)
			(effects
				(font
					(size 1.27 1.27)
					(thickness 0.15)
				)
				(justify left bottom)
				(hide yes)
			)
		)
		(property "Description" ""
			(at 173.99 172.72 0)
			(effects
				(font
					(size 1.27 1.27)
				)
				(hide yes)
			)
		)
		(property "MPN" ""
			(at 163.195 161.29 0)
			(effects
				(font
					(size 1.27 1.27)
					(thickness 0.15)
				)
				(justify left bottom)
				(hide yes)
			)
		)
		(property "Manufacturer" ""
			(at 163.195 166.37 0)
			(effects
				(font
					(size 1.27 1.27)
					(thickness 0.15)
				)
				(justify left bottom)
				(hide yes)
			)
		)
		(property "Author" "Antmicro"
			(at 163.83 163.83 0)
			(effects
				(font
					(size 1.27 1.27)
					(thickness 0.15)
				)
				(justify left bottom)
				(hide yes)
			)
		)
		(property "License" "Apache-2.0"
			(at 163.83 161.29 0)
			(effects
				(font
					(size 1.27 1.27)
					(thickness 0.15)
				)
				(justify left bottom)
				(hide yes)
			)
		)
		(pin "1"
		)
		(instances
			(project "jetson-orin-baseboard"
				(path ""
					(reference "TP30")
					(unit 1)
				)
			)
		)
	)
	(symbol
		(lib_name "GND_3")
		(lib_id "antmicropower:GND")
		(at 62.23 262.89 0)
		(mirror y)
		(unit 1)
		(exclude_from_sim no)
		(in_bom yes)
		(on_board yes)
		(dnp no)
		(property "Reference" "#PWR0352"
			(at 62.23 269.24 0)
			(effects
				(font
					(size 1.27 1.27)
				)
				(justify left bottom)
				(hide yes)
			)
		)
		(property "Value" "GND"
			(at 62.23 266.7 0)
			(effects
				(font
					(size 1.27 1.27)
					(thickness 0.15)
				)
			)
		)
		(property "Footprint" ""
			(at 53.34 270.51 0)
			(effects
				(font
					(size 1.27 1.27)
					(thickness 0.15)
				)
				(justify left bottom)
				(hide yes)
			)
		)
		(property "Datasheet" ""
			(at 53.34 275.59 0)
			(effects
				(font
					(size 1.27 1.27)
					(thickness 0.15)
				)
				(justify left bottom)
				(hide yes)
			)
		)
		(property "Description" ""
			(at 62.23 262.89 0)
			(effects
				(font
					(size 1.27 1.27)
				)
				(hide yes)
			)
		)
		(property "Author" "Antmicro"
			(at 53.34 270.51 0)
			(effects
				(font
					(size 1.27 1.27)
					(thickness 0.15)
				)
				(justify left bottom)
				(hide yes)
			)
		)
		(property "License" "Apache-2.0"
			(at 53.34 273.05 0)
			(effects
				(font
					(size 1.27 1.27)
					(thickness 0.15)
				)
				(justify left bottom)
				(hide yes)
			)
		)
		(pin "1"
		)
		(instances
			(project "jetson-orin-baseboard"
				(path ""
					(reference "#PWR0352")
					(unit 1)
				)
			)
		)
	)
	(symbol
		(lib_id "antmicroResistors0402:R_10M_0402")
		(at 31.75 259.08 90)
		(unit 1)
		(exclude_from_sim no)
		(in_bom no)
		(on_board yes)
		(dnp yes)
		(property "Reference" "R271"
			(at 29.21 255.27 90)
			(effects
				(font
					(size 1.27 1.27)
					(thickness 0.15)
				)
				(justify left)
			)
		)
		(property "Value" "R_10M_0402"
			(at 44.45 238.76 0)
			(effects
				(font
					(size 1.27 1.27)
					(thickness 0.15)
				)
				(justify left bottom)
				(hide yes)
			)
		)
		(property "Footprint" "antmicro-footprints:R_0402_1005Metric"
			(at 46.99 238.76 0)
			(effects
				(font
					(size 1.27 1.27)
					(thickness 0.15)
				)
				(justify left bottom)
				(hide yes)
			)
		)
		(property "Datasheet" "https://www.bourns.com/docs/product-datasheets/cr.pdf"
			(at 49.53 238.76 0)
			(effects
				(font
					(size 1.27 1.27)
					(thickness 0.15)
				)
				(justify left bottom)
				(hide yes)
			)
		)
		(property "Description" ""
			(at 31.75 259.08 0)
			(effects
				(font
					(size 1.27 1.27)
				)
				(hide yes)
			)
		)
		(property "MPN" "CR0402-FX-1005GLF"
			(at 52.07 238.76 0)
			(effects
				(font
					(size 1.27 1.27)
					(thickness 0.15)
				)
				(justify left bottom)
				(hide yes)
			)
		)
		(property "Manufacturer" "Bourns"
			(at 54.61 238.76 0)
			(effects
				(font
					(size 1.27 1.27)
					(thickness 0.15)
				)
				(justify left bottom)
				(hide yes)
			)
		)
		(property "License" "Apache-2.0"
			(at 57.15 238.76 0)
			(effects
				(font
					(size 1.27 1.27)
					(thickness 0.15)
				)
				(justify left bottom)
				(hide yes)
			)
		)
		(property "Author" "Antmicro"
			(at 59.69 238.76 0)
			(effects
				(font
					(size 1.27 1.27)
					(thickness 0.15)
				)
				(justify left bottom)
				(hide yes)
			)
		)
		(property "Val" "10M"
			(at 29.21 257.81 90)
			(effects
				(font
					(size 1.27 1.27)
					(thickness 0.15)
				)
				(justify left)
			)
		)
		(property "Tolerance" "1%"
			(at 41.91 238.76 0)
			(effects
				(font
					(size 1.27 1.27)
				)
				(justify left bottom)
				(hide yes)
			)
		)
		(pin "1"
		)
		(pin "2"
		)
		(instances
			(project "jetson-orin-baseboard"
				(path ""
					(reference "R271")
					(unit 1)
				)
			)
		)
	)
	(symbol
		(lib_id "antmicroCapacitors0402:C_100n_0402")
		(at 271.78 121.92 0)
		(unit 1)
		(exclude_from_sim no)
		(in_bom yes)
		(on_board yes)
		(dnp no)
		(property "Reference" "C61"
			(at 275.59 121.285 0)
			(effects
				(font
					(size 1.27 1.27)
				)
				(justify left bottom)
			)
		)
		(property "Value" "C_100n_0402"
			(at 292.1 132.08 0)
			(effects
				(font
					(size 1.27 1.27)
					(thickness 0.15)
				)
				(justify left bottom)
				(hide yes)
			)
		)
		(property "Footprint" "antmicro-footprints:C_0402_1005Metric"
			(at 292.1 134.62 0)
			(effects
				(font
					(size 1.27 1.27)
					(thickness 0.15)
				)
				(justify left bottom)
				(hide yes)
			)
		)
		(property "Datasheet" "https://www.murata.com/products/productdetail?partno=GRM155R61H104KE14%23"
			(at 292.1 137.16 0)
			(effects
				(font
					(size 1.27 1.27)
					(thickness 0.15)
				)
				(justify left bottom)
				(hide yes)
			)
		)
		(property "Description" ""
			(at 271.78 121.92 0)
			(effects
				(font
					(size 1.27 1.27)
				)
				(hide yes)
			)
		)
		(property "Manufacturer" "Murata"
			(at 292.1 142.24 0)
			(effects
				(font
					(size 1.27 1.27)
					(thickness 0.15)
				)
				(justify left bottom)
				(hide yes)
			)
		)
		(property "MPN" "GRM155R61H104KE14D"
			(at 292.1 139.7 0)
			(effects
				(font
					(size 1.27 1.27)
					(thickness 0.15)
				)
				(justify left bottom)
				(hide yes)
			)
		)
		(property "Val" "100n"
			(at 267.97 123.825 0)
			(effects
				(font
					(size 1.27 1.27)
					(thickness 0.15)
				)
				(justify left bottom)
			)
		)
		(property "License" "Apache-2.0"
			(at 292.1 144.78 0)
			(effects
				(font
					(size 1.27 1.27)
					(thickness 0.15)
				)
				(justify left bottom)
				(hide yes)
			)
		)
		(property "Author" "Antmicro"
			(at 292.1 147.32 0)
			(effects
				(font
					(size 1.27 1.27)
					(thickness 0.15)
				)
				(justify left bottom)
				(hide yes)
			)
		)
		(property "Voltage" "50V"
			(at 292.1 149.86 0)
			(effects
				(font
					(size 1.27 1.27)
				)
				(justify left bottom)
				(hide yes)
			)
		)
		(property "Dielectric" "X5R"
			(at 292.1 152.4 0)
			(effects
				(font
					(size 1.27 1.27)
				)
				(justify left bottom)
				(hide yes)
			)
		)
		(pin "1"
		)
		(pin "2"
		)
		(instances
			(project "jetson-orin-baseboard"
				(path ""
					(reference "C61")
					(unit 1)
				)
			)
		)
	)
	(symbol
		(lib_id "antmicroCapacitors0402:C_10u_0402")
		(at 16.51 45.72 90)
		(unit 1)
		(exclude_from_sim no)
		(in_bom yes)
		(on_board yes)
		(dnp no)
		(property "Reference" "C49"
			(at 17.145 41.275 90)
			(effects
				(font
					(size 1.27 1.27)
					(thickness 0.15)
				)
				(justify right)
			)
		)
		(property "Value" "C_10u_0402"
			(at 26.67 25.4 0)
			(effects
				(font
					(size 1.27 1.27)
					(thickness 0.15)
				)
				(justify left bottom)
				(hide yes)
			)
		)
		(property "Footprint" "antmicro-footprints:C_0402_1005Metric"
			(at 29.21 25.4 0)
			(effects
				(font
					(size 1.27 1.27)
					(thickness 0.15)
				)
				(justify left bottom)
				(hide yes)
			)
		)
		(property "Datasheet" "https://www.yageo.com/en/Chart/Download/pdf/CC0402MRX5R5BB106"
			(at 31.75 25.4 0)
			(effects
				(font
					(size 1.27 1.27)
					(thickness 0.15)
				)
				(justify left bottom)
				(hide yes)
			)
		)
		(property "Description" ""
			(at 16.51 45.72 0)
			(effects
				(font
					(size 1.27 1.27)
				)
				(hide yes)
			)
		)
		(property "MPN" "CC0402MRX5R5BB106"
			(at 34.29 25.4 0)
			(effects
				(font
					(size 1.27 1.27)
					(thickness 0.15)
				)
				(justify left bottom)
				(hide yes)
			)
		)
		(property "Manufacturer" "YAGEO"
			(at 36.83 25.4 0)
			(effects
				(font
					(size 1.27 1.27)
					(thickness 0.15)
				)
				(justify left bottom)
				(hide yes)
			)
		)
		(property "License" "Apache-2.0"
			(at 39.37 25.4 0)
			(effects
				(font
					(size 1.27 1.27)
					(thickness 0.15)
				)
				(justify left bottom)
				(hide yes)
			)
		)
		(property "Author" "Antmicro"
			(at 41.91 25.4 0)
			(effects
				(font
					(size 1.27 1.27)
					(thickness 0.15)
				)
				(justify left bottom)
				(hide yes)
			)
		)
		(property "Val" "10u"
			(at 17.145 45.085 90)
			(effects
				(font
					(size 1.27 1.27)
					(thickness 0.15)
				)
				(justify right)
			)
		)
		(property "Voltage" ""
			(at 44.45 25.4 0)
			(effects
				(font
					(size 1.27 1.27)
				)
				(justify left bottom)
				(hide yes)
			)
		)
		(property "Dielectric" ""
			(at 46.99 25.4 0)
			(effects
				(font
					(size 1.27 1.27)
				)
				(justify left bottom)
				(hide yes)
			)
		)
		(pin "1"
		)
		(pin "2"
		)
		(instances
			(project "jetson-orin-baseboard"
				(path ""
					(reference "C49")
					(unit 1)
				)
			)
		)
	)
	(symbol
		(lib_name "GND_3")
		(lib_id "antmicropower:GND")
		(at 317.5 198.12 0)
		(mirror y)
		(unit 1)
		(exclude_from_sim no)
		(in_bom yes)
		(on_board yes)
		(dnp no)
		(property "Reference" "#PWR0107"
			(at 317.5 204.47 0)
			(effects
				(font
					(size 1.27 1.27)
				)
				(justify left bottom)
				(hide yes)
			)
		)
		(property "Value" "GND"
			(at 317.5 201.93 0)
			(effects
				(font
					(size 1.27 1.27)
					(thickness 0.15)
				)
			)
		)
		(property "Footprint" ""
			(at 308.61 205.74 0)
			(effects
				(font
					(size 1.27 1.27)
					(thickness 0.15)
				)
				(justify left bottom)
				(hide yes)
			)
		)
		(property "Datasheet" ""
			(at 308.61 210.82 0)
			(effects
				(font
					(size 1.27 1.27)
					(thickness 0.15)
				)
				(justify left bottom)
				(hide yes)
			)
		)
		(property "Description" ""
			(at 317.5 198.12 0)
			(effects
				(font
					(size 1.27 1.27)
				)
				(hide yes)
			)
		)
		(property "Author" "Antmicro"
			(at 308.61 205.74 0)
			(effects
				(font
					(size 1.27 1.27)
					(thickness 0.15)
				)
				(justify left bottom)
				(hide yes)
			)
		)
		(property "License" "Apache-2.0"
			(at 308.61 208.28 0)
			(effects
				(font
					(size 1.27 1.27)
					(thickness 0.15)
				)
				(justify left bottom)
				(hide yes)
			)
		)
		(pin "1"
		)
		(instances
			(project "jetson-orin-baseboard"
				(path ""
					(reference "#PWR0107")
					(unit 1)
				)
			)
		)
	)
	(symbol
		(lib_name "C_100n_0402_7")
		(lib_id "antmicroCapacitors0402:C_100n_0402")
		(at 129.54 271.78 270)
		(unit 1)
		(exclude_from_sim no)
		(in_bom yes)
		(on_board yes)
		(dnp no)
		(fields_autoplaced yes)
		(property "Reference" "C159"
			(at 132.08 273.0563 90)
			(effects
				(font
					(size 1.27 1.27)
				)
				(justify left)
			)
		)
		(property "Value" "C_100n_0402"
			(at 119.38 292.1 0)
			(effects
				(font
					(size 1.27 1.27)
					(thickness 0.15)
				)
				(justify left bottom)
				(hide yes)
			)
		)
		(property "Footprint" "antmicro-footprints:C_0402_1005Metric"
			(at 116.84 292.1 0)
			(effects
				(font
					(size 1.27 1.27)
					(thickness 0.15)
				)
				(justify left bottom)
				(hide yes)
			)
		)
		(property "Datasheet" "https://www.murata.com/products/productdetail?partno=GRM155R61H104KE14%23"
			(at 114.3 292.1 0)
			(effects
				(font
					(size 1.27 1.27)
					(thickness 0.15)
				)
				(justify left bottom)
				(hide yes)
			)
		)
		(property "Description" ""
			(at 129.54 271.78 0)
			(effects
				(font
					(size 1.27 1.27)
				)
				(hide yes)
			)
		)
		(property "MPN" "GRM155R61H104KE14D"
			(at 111.76 292.1 0)
			(effects
				(font
					(size 1.27 1.27)
					(thickness 0.15)
				)
				(justify left bottom)
				(hide yes)
			)
		)
		(property "Manufacturer" "Murata"
			(at 109.22 292.1 0)
			(effects
				(font
					(size 1.27 1.27)
					(thickness 0.15)
				)
				(justify left bottom)
				(hide yes)
			)
		)
		(property "Val" "100n"
			(at 132.08 275.5963 90)
			(effects
				(font
					(size 1.27 1.27)
					(thickness 0.15)
				)
				(justify left)
			)
		)
		(property "License" "Apache-2.0"
			(at 106.68 292.1 0)
			(effects
				(font
					(size 1.27 1.27)
					(thickness 0.15)
				)
				(justify left bottom)
				(hide yes)
			)
		)
		(property "Author" "Antmicro"
			(at 104.14 292.1 0)
			(effects
				(font
					(size 1.27 1.27)
					(thickness 0.15)
				)
				(justify left bottom)
				(hide yes)
			)
		)
		(property "Voltage" "50V"
			(at 101.6 292.1 0)
			(effects
				(font
					(size 1.27 1.27)
				)
				(justify left bottom)
				(hide yes)
			)
		)
		(property "Dielectric" "X5R"
			(at 99.06 292.1 0)
			(effects
				(font
					(size 1.27 1.27)
				)
				(justify left bottom)
				(hide yes)
			)
		)
		(pin "1"
		)
		(pin "2"
		)
		(instances
			(project "jetson-orin-baseboard"
				(path ""
					(reference "C159")
					(unit 1)
				)
			)
		)
	)
	(symbol
		(lib_name "TP_0.75mm_SMD_3")
		(lib_id "antmicroTestPoints:TP_0.75mm_SMD")
		(at 107.95 55.88 0)
		(unit 1)
		(exclude_from_sim no)
		(in_bom no)
		(on_board yes)
		(dnp no)
		(property "Reference" "TP24"
			(at 111.76 56.515 0)
			(effects
				(font
					(size 1.27 1.27)
				)
				(justify left bottom)
			)
		)
		(property "Value" "TP_0.75mm_SMD"
			(at 118.11 59.69 0)
			(effects
				(font
					(size 1.27 1.27)
					(thickness 0.15)
				)
				(justify left bottom)
				(hide yes)
			)
		)
		(property "Footprint" "antmicro-footprints:TP_SMD_0.75mm"
			(at 118.11 62.23 0)
			(effects
				(font
					(size 1.27 1.27)
					(thickness 0.15)
				)
				(justify left bottom)
				(hide yes)
			)
		)
		(property "Datasheet" ""
			(at 125.73 68.58 0)
			(effects
				(font
					(size 1.27 1.27)
					(thickness 0.15)
				)
				(justify left bottom)
				(hide yes)
			)
		)
		(property "Description" ""
			(at 107.95 55.88 0)
			(effects
				(font
					(size 1.27 1.27)
				)
				(hide yes)
			)
		)
		(property "MPN" ""
			(at 118.745 67.31 0)
			(effects
				(font
					(size 1.27 1.27)
					(thickness 0.15)
				)
				(justify left bottom)
				(hide yes)
			)
		)
		(property "Manufacturer" ""
			(at 118.745 62.23 0)
			(effects
				(font
					(size 1.27 1.27)
					(thickness 0.15)
				)
				(justify left bottom)
				(hide yes)
			)
		)
		(property "Author" "Antmicro"
			(at 118.11 64.77 0)
			(effects
				(font
					(size 1.27 1.27)
					(thickness 0.15)
				)
				(justify left bottom)
				(hide yes)
			)
		)
		(property "License" "Apache-2.0"
			(at 118.11 67.31 0)
			(effects
				(font
					(size 1.27 1.27)
					(thickness 0.15)
				)
				(justify left bottom)
				(hide yes)
			)
		)
		(pin "1"
		)
		(instances
			(project "jetson-orin-baseboard"
				(path ""
					(reference "TP24")
					(unit 1)
				)
			)
		)
	)
	(symbol
		(lib_name "TP_0.75mm_SMD_4")
		(lib_id "antmicroTestPoints:TP_0.75mm_SMD")
		(at 132.08 49.53 0)
		(unit 1)
		(exclude_from_sim no)
		(in_bom no)
		(on_board yes)
		(dnp no)
		(property "Reference" "TP13"
			(at 135.89 50.165 0)
			(effects
				(font
					(size 1.27 1.27)
				)
				(justify left bottom)
			)
		)
		(property "Value" "TP_0.75mm_SMD"
			(at 142.24 53.34 0)
			(effects
				(font
					(size 1.27 1.27)
					(thickness 0.15)
				)
				(justify left bottom)
				(hide yes)
			)
		)
		(property "Footprint" "antmicro-footprints:TP_SMD_0.75mm"
			(at 142.24 55.88 0)
			(effects
				(font
					(size 1.27 1.27)
					(thickness 0.15)
				)
				(justify left bottom)
				(hide yes)
			)
		)
		(property "Datasheet" ""
			(at 149.86 62.23 0)
			(effects
				(font
					(size 1.27 1.27)
					(thickness 0.15)
				)
				(justify left bottom)
				(hide yes)
			)
		)
		(property "Description" ""
			(at 132.08 49.53 0)
			(effects
				(font
					(size 1.27 1.27)
				)
				(hide yes)
			)
		)
		(property "MPN" ""
			(at 142.875 60.96 0)
			(effects
				(font
					(size 1.27 1.27)
					(thickness 0.15)
				)
				(justify left bottom)
				(hide yes)
			)
		)
		(property "Manufacturer" ""
			(at 142.875 55.88 0)
			(effects
				(font
					(size 1.27 1.27)
					(thickness 0.15)
				)
				(justify left bottom)
				(hide yes)
			)
		)
		(property "Author" "Antmicro"
			(at 142.24 58.42 0)
			(effects
				(font
					(size 1.27 1.27)
					(thickness 0.15)
				)
				(justify left bottom)
				(hide yes)
			)
		)
		(property "License" "Apache-2.0"
			(at 142.24 60.96 0)
			(effects
				(font
					(size 1.27 1.27)
					(thickness 0.15)
				)
				(justify left bottom)
				(hide yes)
			)
		)
		(pin "1"
		)
		(instances
			(project "jetson-orin-baseboard"
				(path ""
					(reference "TP13")
					(unit 1)
				)
			)
		)
	)
	(symbol
		(lib_id "antmicroResistors0402:R_1k_0402")
		(at 262.89 165.1 0)
		(unit 1)
		(exclude_from_sim no)
		(in_bom no)
		(on_board yes)
		(dnp yes)
		(property "Reference" "R95"
			(at 268.605 164.465 0)
			(effects
				(font
					(size 1.27 1.27)
				)
				(justify left bottom)
			)
		)
		(property "Value" "R_1k_0402"
			(at 283.21 177.8 0)
			(effects
				(font
					(size 1.27 1.27)
					(thickness 0.15)
				)
				(justify left bottom)
				(hide yes)
			)
		)
		(property "Footprint" "antmicro-footprints:R_0402_1005Metric"
			(at 283.21 180.34 0)
			(effects
				(font
					(size 1.27 1.27)
					(thickness 0.15)
				)
				(justify left bottom)
				(hide yes)
			)
		)
		(property "Datasheet" "https://www.bourns.com/docs/product-datasheets/cr.pdf"
			(at 283.21 182.88 0)
			(effects
				(font
					(size 1.27 1.27)
					(thickness 0.15)
				)
				(justify left bottom)
				(hide yes)
			)
		)
		(property "Description" ""
			(at 262.89 165.1 0)
			(effects
				(font
					(size 1.27 1.27)
				)
				(hide yes)
			)
		)
		(property "Manufacturer" "Bourns"
			(at 283.21 187.96 0)
			(effects
				(font
					(size 1.27 1.27)
					(thickness 0.15)
				)
				(justify left bottom)
				(hide yes)
			)
		)
		(property "MPN" "CR0402-FX-1001GLF"
			(at 283.21 185.42 0)
			(effects
				(font
					(size 1.27 1.27)
					(thickness 0.15)
				)
				(justify left bottom)
				(hide yes)
			)
		)
		(property "Val" "1k"
			(at 260.35 164.465 0)
			(effects
				(font
					(size 1.27 1.27)
					(thickness 0.15)
				)
				(justify left bottom)
			)
		)
		(property "License" "Apache-2.0"
			(at 283.21 190.5 0)
			(effects
				(font
					(size 1.27 1.27)
					(thickness 0.15)
				)
				(justify left bottom)
				(hide yes)
			)
		)
		(property "Author" "Antmicro"
			(at 283.21 193.04 0)
			(effects
				(font
					(size 1.27 1.27)
					(thickness 0.15)
				)
				(justify left bottom)
				(hide yes)
			)
		)
		(property "Tolerance" "1%"
			(at 283.21 175.26 0)
			(effects
				(font
					(size 1.27 1.27)
				)
				(justify left bottom)
				(hide yes)
			)
		)
		(pin "1"
		)
		(pin "2"
		)
		(instances
			(project "jetson-orin-baseboard"
				(path ""
					(reference "R95")
					(unit 1)
				)
			)
		)
	)
	(symbol
		(lib_id "antmicroResistors0402:R_2M_0402")
		(at 361.95 133.35 270)
		(unit 1)
		(exclude_from_sim no)
		(in_bom yes)
		(on_board yes)
		(dnp no)
		(property "Reference" "R110"
			(at 363.22 134.62 90)
			(effects
				(font
					(size 1.27 1.27)
					(thickness 0.15)
				)
				(justify left)
			)
		)
		(property "Value" "R_2M_0402"
			(at 349.25 153.67 0)
			(effects
				(font
					(size 1.27 1.27)
					(thickness 0.15)
				)
				(justify left bottom)
				(hide yes)
			)
		)
		(property "Footprint" "antmicro-footprints:R_0402_1005Metric"
			(at 346.71 153.67 0)
			(effects
				(font
					(size 1.27 1.27)
					(thickness 0.15)
				)
				(justify left bottom)
				(hide yes)
			)
		)
		(property "Datasheet" "https://www.mouser.com/datasheet/2/447/YAGEO_PYu_RC_Group_51_RoHS_L_12-3313492.pdf"
			(at 344.17 153.67 0)
			(effects
				(font
					(size 1.27 1.27)
					(thickness 0.15)
				)
				(justify left bottom)
				(hide yes)
			)
		)
		(property "Description" "SMD Chip Resistor, 2 Mohm, ± 1%, 62.5 mW, 0402 [1005 Metric], Thick Film, General Purpose"
			(at 361.95 133.35 0)
			(effects
				(font
					(size 1.27 1.27)
				)
				(hide yes)
			)
		)
		(property "MPN" "RC0402FR-072ML"
			(at 341.63 153.67 0)
			(effects
				(font
					(size 1.27 1.27)
					(thickness 0.15)
				)
				(justify left bottom)
				(hide yes)
			)
		)
		(property "Manufacturer" "YAGEO"
			(at 339.09 153.67 0)
			(effects
				(font
					(size 1.27 1.27)
					(thickness 0.15)
				)
				(justify left bottom)
				(hide yes)
			)
		)
		(property "License" "Apache-2.0"
			(at 336.55 153.67 0)
			(effects
				(font
					(size 1.27 1.27)
					(thickness 0.15)
				)
				(justify left bottom)
				(hide yes)
			)
		)
		(property "Author" "Antmicro"
			(at 334.01 153.67 0)
			(effects
				(font
					(size 1.27 1.27)
					(thickness 0.15)
				)
				(justify left bottom)
				(hide yes)
			)
		)
		(property "Val" "2M"
			(at 363.22 137.16 90)
			(effects
				(font
					(size 1.27 1.27)
					(thickness 0.15)
				)
				(justify left)
			)
		)
		(property "Tolerance" "1%"
			(at 351.79 153.67 0)
			(effects
				(font
					(size 1.27 1.27)
				)
				(justify left bottom)
				(hide yes)
			)
		)
		(pin "1"
		)
		(pin "2"
		)
		(instances
			(project "jetson-orin-baseboard"
				(path ""
					(reference "R110")
					(unit 1)
				)
			)
		)
	)
	(symbol
		(lib_name "R_0R_0402_3")
		(lib_id "antmicroResistors0402:R_0R_0402")
		(at 113.03 52.07 180)
		(unit 1)
		(exclude_from_sim no)
		(in_bom yes)
		(on_board yes)
		(dnp no)
		(property "Reference" "R65"
			(at 113.03 51.435 0)
			(effects
				(font
					(size 1.27 1.27)
				)
				(justify right top)
			)
		)
		(property "Value" "R_0R_0402"
			(at 92.71 39.37 0)
			(effects
				(font
					(size 1.27 1.27)
					(thickness 0.15)
				)
				(justify left bottom)
				(hide yes)
			)
		)
		(property "Footprint" "antmicro-footprints:R_0402_1005Metric"
			(at 92.71 36.83 0)
			(effects
				(font
					(size 1.27 1.27)
					(thickness 0.15)
				)
				(justify left bottom)
				(hide yes)
			)
		)
		(property "Datasheet" "https://industrial.panasonic.com/cdbs/www-data/pdf/RDA0000/AOA0000C301.pdf"
			(at 92.71 34.29 0)
			(effects
				(font
					(size 1.27 1.27)
					(thickness 0.15)
				)
				(justify left bottom)
				(hide yes)
			)
		)
		(property "Description" ""
			(at 113.03 52.07 0)
			(effects
				(font
					(size 1.27 1.27)
				)
				(hide yes)
			)
		)
		(property "Manufacturer" "Panasonic"
			(at 92.71 29.21 0)
			(effects
				(font
					(size 1.27 1.27)
					(thickness 0.15)
				)
				(justify left bottom)
				(hide yes)
			)
		)
		(property "MPN" "ERJ2GE0R00X"
			(at 92.71 31.75 0)
			(effects
				(font
					(size 1.27 1.27)
					(thickness 0.15)
				)
				(justify left bottom)
				(hide yes)
			)
		)
		(property "Val" "0R"
			(at 105.41 51.435 0)
			(effects
				(font
					(size 1.27 1.27)
					(thickness 0.15)
				)
				(justify right top)
			)
		)
		(property "License" "Apache-2.0"
			(at 92.71 26.67 0)
			(effects
				(font
					(size 1.27 1.27)
					(thickness 0.15)
				)
				(justify left bottom)
				(hide yes)
			)
		)
		(property "Author" "Antmicro"
			(at 92.71 24.13 0)
			(effects
				(font
					(size 1.27 1.27)
					(thickness 0.15)
				)
				(justify left bottom)
				(hide yes)
			)
		)
		(property "Tolerance" "~"
			(at 92.71 41.91 0)
			(effects
				(font
					(size 1.27 1.27)
				)
				(justify left bottom)
				(hide yes)
			)
		)
		(property "Current" "1A"
			(at 92.71 21.59 0)
			(effects
				(font
					(size 1.27 1.27)
					(thickness 0.15)
				)
				(justify left bottom)
				(hide yes)
			)
		)
		(pin "1"
		)
		(pin "2"
		)
		(instances
			(project "jetson-orin-baseboard"
				(path ""
					(reference "R65")
					(unit 1)
				)
			)
		)
	)
	(symbol
		(lib_name "GND_3")
		(lib_id "antmicropower:GND")
		(at 332.74 137.16 0)
		(mirror y)
		(unit 1)
		(exclude_from_sim no)
		(in_bom yes)
		(on_board yes)
		(dnp no)
		(property "Reference" "#PWR099"
			(at 332.74 143.51 0)
			(effects
				(font
					(size 1.27 1.27)
				)
				(justify left bottom)
				(hide yes)
			)
		)
		(property "Value" "GND"
			(at 332.74 140.97 0)
			(effects
				(font
					(size 1.27 1.27)
					(thickness 0.15)
				)
			)
		)
		(property "Footprint" ""
			(at 323.85 144.78 0)
			(effects
				(font
					(size 1.27 1.27)
					(thickness 0.15)
				)
				(justify left bottom)
				(hide yes)
			)
		)
		(property "Datasheet" ""
			(at 323.85 149.86 0)
			(effects
				(font
					(size 1.27 1.27)
					(thickness 0.15)
				)
				(justify left bottom)
				(hide yes)
			)
		)
		(property "Description" ""
			(at 332.74 137.16 0)
			(effects
				(font
					(size 1.27 1.27)
				)
				(hide yes)
			)
		)
		(property "Author" "Antmicro"
			(at 323.85 144.78 0)
			(effects
				(font
					(size 1.27 1.27)
					(thickness 0.15)
				)
				(justify left bottom)
				(hide yes)
			)
		)
		(property "License" "Apache-2.0"
			(at 323.85 147.32 0)
			(effects
				(font
					(size 1.27 1.27)
					(thickness 0.15)
				)
				(justify left bottom)
				(hide yes)
			)
		)
		(pin "1"
		)
		(instances
			(project "jetson-orin-baseboard"
				(path ""
					(reference "#PWR099")
					(unit 1)
				)
			)
		)
	)
	(symbol
		(lib_id "antmicroCapacitors0402:C_1u_25V_0402")
		(at 317.5 191.77 270)
		(unit 1)
		(exclude_from_sim no)
		(in_bom yes)
		(on_board yes)
		(dnp no)
		(property "Reference" "C147"
			(at 319.405 193.04 90)
			(effects
				(font
					(size 1.27 1.27)
				)
				(justify left)
			)
		)
		(property "Value" "C_1u_25V_0402"
			(at 307.34 212.09 0)
			(effects
				(font
					(size 1.27 1.27)
					(thickness 0.15)
				)
				(justify left bottom)
				(hide yes)
			)
		)
		(property "Footprint" "antmicro-footprints:C_0402_1005Metric"
			(at 304.8 212.09 0)
			(effects
				(font
					(size 1.27 1.27)
					(thickness 0.15)
				)
				(justify left bottom)
				(hide yes)
			)
		)
		(property "Datasheet" "https://www.murata.com/products/productdetail?partno=GRM155R61E105KE11%23"
			(at 302.26 212.09 0)
			(effects
				(font
					(size 1.27 1.27)
					(thickness 0.15)
				)
				(justify left bottom)
				(hide yes)
			)
		)
		(property "Description" ""
			(at 317.5 191.77 0)
			(effects
				(font
					(size 1.27 1.27)
				)
				(hide yes)
			)
		)
		(property "Manufacturer" "Murata"
			(at 297.18 212.09 0)
			(effects
				(font
					(size 1.27 1.27)
					(thickness 0.15)
				)
				(justify left bottom)
				(hide yes)
			)
		)
		(property "MPN" "GRM155R61E105KE11J"
			(at 299.72 212.09 0)
			(effects
				(font
					(size 1.27 1.27)
					(thickness 0.15)
				)
				(justify left bottom)
				(hide yes)
			)
		)
		(property "Val" "1u"
			(at 319.405 195.58 90)
			(effects
				(font
					(size 1.27 1.27)
					(thickness 0.15)
				)
				(justify left)
			)
		)
		(property "License" "Apache-2.0"
			(at 294.64 212.09 0)
			(effects
				(font
					(size 1.27 1.27)
					(thickness 0.15)
				)
				(justify left bottom)
				(hide yes)
			)
		)
		(property "Author" "Antmicro"
			(at 292.1 212.09 0)
			(effects
				(font
					(size 1.27 1.27)
					(thickness 0.15)
				)
				(justify left bottom)
				(hide yes)
			)
		)
		(property "Voltage" "25V"
			(at 289.56 212.09 0)
			(effects
				(font
					(size 1.27 1.27)
				)
				(justify left bottom)
				(hide yes)
			)
		)
		(property "Dielectric" "X5R"
			(at 287.02 212.09 0)
			(effects
				(font
					(size 1.27 1.27)
				)
				(justify left bottom)
				(hide yes)
			)
		)
		(pin "1"
		)
		(pin "2"
		)
		(instances
			(project "jetson-orin-baseboard"
				(path ""
					(reference "C147")
					(unit 1)
				)
			)
		)
	)
	(symbol
		(lib_name "GND_3")
		(lib_id "antmicropower:GND")
		(at 341.63 231.14 0)
		(mirror y)
		(unit 1)
		(exclude_from_sim no)
		(in_bom yes)
		(on_board yes)
		(dnp no)
		(property "Reference" "#PWR091"
			(at 341.63 237.49 0)
			(effects
				(font
					(size 1.27 1.27)
				)
				(justify left bottom)
				(hide yes)
			)
		)
		(property "Value" "GND"
			(at 341.63 234.95 0)
			(effects
				(font
					(size 1.27 1.27)
					(thickness 0.15)
				)
			)
		)
		(property "Footprint" ""
			(at 332.74 238.76 0)
			(effects
				(font
					(size 1.27 1.27)
					(thickness 0.15)
				)
				(justify left bottom)
				(hide yes)
			)
		)
		(property "Datasheet" ""
			(at 332.74 243.84 0)
			(effects
				(font
					(size 1.27 1.27)
					(thickness 0.15)
				)
				(justify left bottom)
				(hide yes)
			)
		)
		(property "Description" ""
			(at 341.63 231.14 0)
			(effects
				(font
					(size 1.27 1.27)
				)
				(hide yes)
			)
		)
		(property "Author" "Antmicro"
			(at 332.74 238.76 0)
			(effects
				(font
					(size 1.27 1.27)
					(thickness 0.15)
				)
				(justify left bottom)
				(hide yes)
			)
		)
		(property "License" "Apache-2.0"
			(at 332.74 241.3 0)
			(effects
				(font
					(size 1.27 1.27)
					(thickness 0.15)
				)
				(justify left bottom)
				(hide yes)
			)
		)
		(pin "1"
		)
		(instances
			(project "jetson-orin-baseboard"
				(path ""
					(reference "#PWR091")
					(unit 1)
				)
			)
		)
	)
	(symbol
		(lib_name "LED_G_0603_LTST-C190GKT_5")
		(lib_id "antmicroLEDIndicationDiscrete:LED_G_0603_LTST-C190GKT")
		(at 351.79 203.2 90)
		(unit 1)
		(exclude_from_sim no)
		(in_bom yes)
		(on_board yes)
		(dnp no)
		(fields_autoplaced yes)
		(property "Reference" "D8"
			(at 353.695 199.39 90)
			(effects
				(font
					(size 1.27 1.27)
				)
				(justify right)
			)
		)
		(property "Value" "LED_G_0603_LTST-C190GKT"
			(at 359.41 180.34 0)
			(effects
				(font
					(size 1.27 1.27)
					(thickness 0.15)
				)
				(justify left bottom)
				(hide yes)
			)
		)
		(property "Footprint" "antmicro-footprints:LED_0603_1608Metric_G"
			(at 361.95 180.34 0)
			(effects
				(font
					(size 1.27 1.27)
					(thickness 0.15)
				)
				(justify left bottom)
				(hide yes)
			)
		)
		(property "Datasheet" "https://media.digikey.com/pdf/Data%20Sheets/Lite-On%20PDFs/LTST-C190GKT.pdf"
			(at 364.49 180.34 0)
			(effects
				(font
					(size 1.27 1.27)
					(thickness 0.15)
				)
				(justify left bottom)
				(hide yes)
			)
		)
		(property "Description" ""
			(at 351.79 203.2 0)
			(effects
				(font
					(size 1.27 1.27)
				)
				(hide yes)
			)
		)
		(property "MPN" "LTST-C190GKT"
			(at 367.03 180.34 0)
			(effects
				(font
					(size 1.27 1.27)
					(thickness 0.15)
				)
				(justify left bottom)
				(hide yes)
			)
		)
		(property "Manufacturer" "Lite-On"
			(at 369.57 180.34 0)
			(effects
				(font
					(size 1.27 1.27)
					(thickness 0.15)
				)
				(justify left bottom)
				(hide yes)
			)
		)
		(property "Author" "Antmicro"
			(at 372.11 180.34 0)
			(effects
				(font
					(size 1.27 1.27)
					(thickness 0.15)
				)
				(justify left bottom)
				(hide yes)
			)
		)
		(property "License" "Apache-2.0"
			(at 374.65 180.34 0)
			(effects
				(font
					(size 1.27 1.27)
					(thickness 0.15)
				)
				(justify left bottom)
				(hide yes)
			)
		)
		(property "Color" "Green"
			(at 353.695 201.93 90)
			(effects
				(font
					(size 1.27 1.27)
				)
				(justify right)
			)
		)
		(pin "1"
		)
		(pin "2"
		)
		(instances
			(project "jetson-orin-baseboard"
				(path ""
					(reference "D8")
					(unit 1)
				)
			)
		)
	)
	(symbol
		(lib_id "antmicroResistors0402:R_1k_0402")
		(at 93.98 241.3 90)
		(unit 1)
		(exclude_from_sim no)
		(in_bom yes)
		(on_board yes)
		(dnp no)
		(fields_autoplaced yes)
		(property "Reference" "R111"
			(at 96.52 237.49 90)
			(effects
				(font
					(size 1.27 1.27)
					(thickness 0.15)
				)
				(justify right)
			)
		)
		(property "Value" "R_1k_0402"
			(at 106.68 220.98 0)
			(effects
				(font
					(size 1.27 1.27)
					(thickness 0.15)
				)
				(justify left bottom)
				(hide yes)
			)
		)
		(property "Footprint" "antmicro-footprints:R_0402_1005Metric"
			(at 109.22 220.98 0)
			(effects
				(font
					(size 1.27 1.27)
					(thickness 0.15)
				)
				(justify left bottom)
				(hide yes)
			)
		)
		(property "Datasheet" "https://www.bourns.com/docs/product-datasheets/cr.pdf"
			(at 111.76 220.98 0)
			(effects
				(font
					(size 1.27 1.27)
					(thickness 0.15)
				)
				(justify left bottom)
				(hide yes)
			)
		)
		(property "Description" ""
			(at 93.98 241.3 0)
			(effects
				(font
					(size 1.27 1.27)
				)
				(hide yes)
			)
		)
		(property "MPN" "CR0402-FX-1001GLF"
			(at 114.3 220.98 0)
			(effects
				(font
					(size 1.27 1.27)
					(thickness 0.15)
				)
				(justify left bottom)
				(hide yes)
			)
		)
		(property "Manufacturer" "Bourns"
			(at 116.84 220.98 0)
			(effects
				(font
					(size 1.27 1.27)
					(thickness 0.15)
				)
				(justify left bottom)
				(hide yes)
			)
		)
		(property "License" "Apache-2.0"
			(at 119.38 220.98 0)
			(effects
				(font
					(size 1.27 1.27)
					(thickness 0.15)
				)
				(justify left bottom)
				(hide yes)
			)
		)
		(property "Author" "Antmicro"
			(at 121.92 220.98 0)
			(effects
				(font
					(size 1.27 1.27)
					(thickness 0.15)
				)
				(justify left bottom)
				(hide yes)
			)
		)
		(property "Val" "1k"
			(at 96.52 240.03 90)
			(effects
				(font
					(size 1.27 1.27)
					(thickness 0.15)
				)
				(justify right)
			)
		)
		(property "Tolerance" "1%"
			(at 104.14 220.98 0)
			(effects
				(font
					(size 1.27 1.27)
				)
				(justify left bottom)
				(hide yes)
			)
		)
		(pin "2"
		)
		(pin "1"
		)
		(instances
			(project "jetson-orin-baseboard"
				(path ""
					(reference "R111")
					(unit 1)
				)
			)
		)
	)
	(symbol
		(lib_id "antmicroResistors0402:R_1k_0402")
		(at 262.89 139.7 0)
		(unit 1)
		(exclude_from_sim no)
		(in_bom no)
		(on_board yes)
		(dnp yes)
		(property "Reference" "R85"
			(at 268.605 139.065 0)
			(effects
				(font
					(size 1.27 1.27)
				)
				(justify left bottom)
			)
		)
		(property "Value" "R_1k_0402"
			(at 283.21 152.4 0)
			(effects
				(font
					(size 1.27 1.27)
					(thickness 0.15)
				)
				(justify left bottom)
				(hide yes)
			)
		)
		(property "Footprint" "antmicro-footprints:R_0402_1005Metric"
			(at 283.21 154.94 0)
			(effects
				(font
					(size 1.27 1.27)
					(thickness 0.15)
				)
				(justify left bottom)
				(hide yes)
			)
		)
		(property "Datasheet" "https://www.bourns.com/docs/product-datasheets/cr.pdf"
			(at 283.21 157.48 0)
			(effects
				(font
					(size 1.27 1.27)
					(thickness 0.15)
				)
				(justify left bottom)
				(hide yes)
			)
		)
		(property "Description" ""
			(at 262.89 139.7 0)
			(effects
				(font
					(size 1.27 1.27)
				)
				(hide yes)
			)
		)
		(property "Manufacturer" "Bourns"
			(at 283.21 162.56 0)
			(effects
				(font
					(size 1.27 1.27)
					(thickness 0.15)
				)
				(justify left bottom)
				(hide yes)
			)
		)
		(property "MPN" "CR0402-FX-1001GLF"
			(at 283.21 160.02 0)
			(effects
				(font
					(size 1.27 1.27)
					(thickness 0.15)
				)
				(justify left bottom)
				(hide yes)
			)
		)
		(property "Val" "1k"
			(at 260.35 139.065 0)
			(effects
				(font
					(size 1.27 1.27)
					(thickness 0.15)
				)
				(justify left bottom)
			)
		)
		(property "License" "Apache-2.0"
			(at 283.21 165.1 0)
			(effects
				(font
					(size 1.27 1.27)
					(thickness 0.15)
				)
				(justify left bottom)
				(hide yes)
			)
		)
		(property "Author" "Antmicro"
			(at 283.21 167.64 0)
			(effects
				(font
					(size 1.27 1.27)
					(thickness 0.15)
				)
				(justify left bottom)
				(hide yes)
			)
		)
		(property "Tolerance" "1%"
			(at 283.21 149.86 0)
			(effects
				(font
					(size 1.27 1.27)
				)
				(justify left bottom)
				(hide yes)
			)
		)
		(pin "1"
		)
		(pin "2"
		)
		(instances
			(project "jetson-orin-baseboard"
				(path ""
					(reference "R85")
					(unit 1)
				)
			)
		)
	)
	(symbol
		(lib_id "antmicroCapacitors0402:C_100n_0402")
		(at 262.89 35.56 90)
		(mirror x)
		(unit 1)
		(exclude_from_sim no)
		(in_bom yes)
		(on_board yes)
		(dnp no)
		(property "Reference" "C57"
			(at 264.795 36.83 90)
			(effects
				(font
					(size 1.27 1.27)
				)
				(justify right)
			)
		)
		(property "Value" "C_100n_0402"
			(at 273.05 55.88 0)
			(effects
				(font
					(size 1.27 1.27)
					(thickness 0.15)
				)
				(justify left bottom)
				(hide yes)
			)
		)
		(property "Footprint" "antmicro-footprints:C_0402_1005Metric"
			(at 275.59 55.88 0)
			(effects
				(font
					(size 1.27 1.27)
					(thickness 0.15)
				)
				(justify left bottom)
				(hide yes)
			)
		)
		(property "Datasheet" "https://www.murata.com/products/productdetail?partno=GRM155R61H104KE14%23"
			(at 278.13 55.88 0)
			(effects
				(font
					(size 1.27 1.27)
					(thickness 0.15)
				)
				(justify left bottom)
				(hide yes)
			)
		)
		(property "Description" ""
			(at 262.89 35.56 0)
			(effects
				(font
					(size 1.27 1.27)
				)
				(hide yes)
			)
		)
		(property "Manufacturer" "Murata"
			(at 283.21 55.88 0)
			(effects
				(font
					(size 1.27 1.27)
					(thickness 0.15)
				)
				(justify left bottom)
				(hide yes)
			)
		)
		(property "MPN" "GRM155R61H104KE14D"
			(at 280.67 55.88 0)
			(effects
				(font
					(size 1.27 1.27)
					(thickness 0.15)
				)
				(justify left bottom)
				(hide yes)
			)
		)
		(property "Val" "100n"
			(at 264.795 39.37 90)
			(effects
				(font
					(size 1.27 1.27)
					(thickness 0.15)
				)
				(justify right)
			)
		)
		(property "License" "Apache-2.0"
			(at 285.75 55.88 0)
			(effects
				(font
					(size 1.27 1.27)
					(thickness 0.15)
				)
				(justify left bottom)
				(hide yes)
			)
		)
		(property "Author" "Antmicro"
			(at 288.29 55.88 0)
			(effects
				(font
					(size 1.27 1.27)
					(thickness 0.15)
				)
				(justify left bottom)
				(hide yes)
			)
		)
		(property "Voltage" "50V"
			(at 290.83 55.88 0)
			(effects
				(font
					(size 1.27 1.27)
				)
				(justify left bottom)
				(hide yes)
			)
		)
		(property "Dielectric" "X5R"
			(at 293.37 55.88 0)
			(effects
				(font
					(size 1.27 1.27)
				)
				(justify left bottom)
				(hide yes)
			)
		)
		(pin "1"
		)
		(pin "2"
		)
		(instances
			(project "jetson-orin-baseboard"
				(path ""
					(reference "C57")
					(unit 1)
				)
			)
		)
	)
	(symbol
		(lib_name "GND_3")
		(lib_id "antmicropower:GND")
		(at 386.08 48.26 0)
		(mirror y)
		(unit 1)
		(exclude_from_sim no)
		(in_bom yes)
		(on_board yes)
		(dnp no)
		(property "Reference" "#PWR0106"
			(at 386.08 54.61 0)
			(effects
				(font
					(size 1.27 1.27)
				)
				(justify left bottom)
				(hide yes)
			)
		)
		(property "Value" "GND"
			(at 386.08 52.07 0)
			(effects
				(font
					(size 1.27 1.27)
					(thickness 0.15)
				)
			)
		)
		(property "Footprint" ""
			(at 377.19 55.88 0)
			(effects
				(font
					(size 1.27 1.27)
					(thickness 0.15)
				)
				(justify left bottom)
				(hide yes)
			)
		)
		(property "Datasheet" ""
			(at 377.19 60.96 0)
			(effects
				(font
					(size 1.27 1.27)
					(thickness 0.15)
				)
				(justify left bottom)
				(hide yes)
			)
		)
		(property "Description" ""
			(at 386.08 48.26 0)
			(effects
				(font
					(size 1.27 1.27)
				)
				(hide yes)
			)
		)
		(property "Author" "Antmicro"
			(at 377.19 55.88 0)
			(effects
				(font
					(size 1.27 1.27)
					(thickness 0.15)
				)
				(justify left bottom)
				(hide yes)
			)
		)
		(property "License" "Apache-2.0"
			(at 377.19 58.42 0)
			(effects
				(font
					(size 1.27 1.27)
					(thickness 0.15)
				)
				(justify left bottom)
				(hide yes)
			)
		)
		(pin "1"
		)
		(instances
			(project "jetson-orin-baseboard"
				(path ""
					(reference "#PWR0106")
					(unit 1)
				)
			)
		)
	)
	(symbol
		(lib_id "antmicroCapacitors0402:C_100n_0402")
		(at 184.15 116.84 0)
		(mirror x)
		(unit 1)
		(exclude_from_sim no)
		(in_bom yes)
		(on_board yes)
		(dnp no)
		(property "Reference" "C140"
			(at 190.5 115.57 0)
			(effects
				(font
					(size 1.27 1.27)
				)
			)
		)
		(property "Value" "C_100n_0402"
			(at 204.47 106.68 0)
			(effects
				(font
					(size 1.27 1.27)
					(thickness 0.15)
				)
				(justify left bottom)
				(hide yes)
			)
		)
		(property "Footprint" "antmicro-footprints:C_0402_1005Metric"
			(at 204.47 104.14 0)
			(effects
				(font
					(size 1.27 1.27)
					(thickness 0.15)
				)
				(justify left bottom)
				(hide yes)
			)
		)
		(property "Datasheet" "https://www.murata.com/products/productdetail?partno=GRM155R61H104KE14%23"
			(at 204.47 101.6 0)
			(effects
				(font
					(size 1.27 1.27)
					(thickness 0.15)
				)
				(justify left bottom)
				(hide yes)
			)
		)
		(property "Description" ""
			(at 184.15 116.84 0)
			(effects
				(font
					(size 1.27 1.27)
				)
				(hide yes)
			)
		)
		(property "Manufacturer" "Murata"
			(at 204.47 96.52 0)
			(effects
				(font
					(size 1.27 1.27)
					(thickness 0.15)
				)
				(justify left bottom)
				(hide yes)
			)
		)
		(property "MPN" "GRM155R61H104KE14D"
			(at 204.47 99.06 0)
			(effects
				(font
					(size 1.27 1.27)
					(thickness 0.15)
				)
				(justify left bottom)
				(hide yes)
			)
		)
		(property "Val" "100n"
			(at 182.88 118.11 0)
			(effects
				(font
					(size 1.27 1.27)
					(thickness 0.15)
				)
			)
		)
		(property "License" "Apache-2.0"
			(at 204.47 93.98 0)
			(effects
				(font
					(size 1.27 1.27)
					(thickness 0.15)
				)
				(justify left bottom)
				(hide yes)
			)
		)
		(property "Author" "Antmicro"
			(at 204.47 91.44 0)
			(effects
				(font
					(size 1.27 1.27)
					(thickness 0.15)
				)
				(justify left bottom)
				(hide yes)
			)
		)
		(property "Voltage" "50V"
			(at 204.47 88.9 0)
			(effects
				(font
					(size 1.27 1.27)
				)
				(justify left bottom)
				(hide yes)
			)
		)
		(property "Dielectric" "X5R"
			(at 204.47 86.36 0)
			(effects
				(font
					(size 1.27 1.27)
				)
				(justify left bottom)
				(hide yes)
			)
		)
		(pin "1"
		)
		(pin "2"
		)
		(instances
			(project "jetson-orin-baseboard"
				(path ""
					(reference "C140")
					(unit 1)
				)
			)
		)
	)
	(symbol
		(lib_id "antmicroResistors0402:R_1k_0402")
		(at 262.89 160.02 0)
		(unit 1)
		(exclude_from_sim no)
		(in_bom no)
		(on_board yes)
		(dnp yes)
		(property "Reference" "R93"
			(at 268.605 159.385 0)
			(effects
				(font
					(size 1.27 1.27)
				)
				(justify left bottom)
			)
		)
		(property "Value" "R_1k_0402"
			(at 283.21 172.72 0)
			(effects
				(font
					(size 1.27 1.27)
					(thickness 0.15)
				)
				(justify left bottom)
				(hide yes)
			)
		)
		(property "Footprint" "antmicro-footprints:R_0402_1005Metric"
			(at 283.21 175.26 0)
			(effects
				(font
					(size 1.27 1.27)
					(thickness 0.15)
				)
				(justify left bottom)
				(hide yes)
			)
		)
		(property "Datasheet" "https://www.bourns.com/docs/product-datasheets/cr.pdf"
			(at 283.21 177.8 0)
			(effects
				(font
					(size 1.27 1.27)
					(thickness 0.15)
				)
				(justify left bottom)
				(hide yes)
			)
		)
		(property "Description" ""
			(at 262.89 160.02 0)
			(effects
				(font
					(size 1.27 1.27)
				)
				(hide yes)
			)
		)
		(property "Manufacturer" "Bourns"
			(at 283.21 182.88 0)
			(effects
				(font
					(size 1.27 1.27)
					(thickness 0.15)
				)
				(justify left bottom)
				(hide yes)
			)
		)
		(property "MPN" "CR0402-FX-1001GLF"
			(at 283.21 180.34 0)
			(effects
				(font
					(size 1.27 1.27)
					(thickness 0.15)
				)
				(justify left bottom)
				(hide yes)
			)
		)
		(property "Val" "1k"
			(at 260.35 159.385 0)
			(effects
				(font
					(size 1.27 1.27)
					(thickness 0.15)
				)
				(justify left bottom)
			)
		)
		(property "License" "Apache-2.0"
			(at 283.21 185.42 0)
			(effects
				(font
					(size 1.27 1.27)
					(thickness 0.15)
				)
				(justify left bottom)
				(hide yes)
			)
		)
		(property "Author" "Antmicro"
			(at 283.21 187.96 0)
			(effects
				(font
					(size 1.27 1.27)
					(thickness 0.15)
				)
				(justify left bottom)
				(hide yes)
			)
		)
		(property "Tolerance" "1%"
			(at 283.21 170.18 0)
			(effects
				(font
					(size 1.27 1.27)
				)
				(justify left bottom)
				(hide yes)
			)
		)
		(pin "1"
		)
		(pin "2"
		)
		(instances
			(project "jetson-orin-baseboard"
				(path ""
					(reference "R93")
					(unit 1)
				)
			)
		)
	)
	(symbol
		(lib_name "TPS65988DHRSHR_1")
		(lib_id "antmicroInterfaceControllers:TPS65988DHRSHR")
		(at 53.34 41.91 0)
		(unit 1)
		(exclude_from_sim no)
		(in_bom yes)
		(on_board yes)
		(dnp no)
		(fields_autoplaced yes)
		(property "Reference" "U6"
			(at 71.12 34.29 0)
			(effects
				(font
					(size 1.27 1.27)
				)
			)
		)
		(property "Value" "TPS65988DHRSHR"
			(at 102.87 46.99 0)
			(effects
				(font
					(size 1.27 1.27)
					(thickness 0.15)
				)
				(justify left bottom)
				(hide yes)
			)
		)
		(property "Footprint" "antmicro-footprints:IC_TPS65987DDHRSHR"
			(at 102.87 49.53 0)
			(effects
				(font
					(size 1.27 1.27)
					(thickness 0.15)
				)
				(justify left bottom)
				(hide yes)
			)
		)
		(property "Datasheet" "https://www.ti.com/lit/ds/symlink/tps65988.pdf?ts=1662726631004&ref_url=https%253A%252F%252Fwww.ti.com%252Fproduct%252FTPS65988"
			(at 102.87 52.07 0)
			(effects
				(font
					(size 1.27 1.27)
					(thickness 0.15)
				)
				(justify left bottom)
				(hide yes)
			)
		)
		(property "Description" ""
			(at 53.34 41.91 0)
			(effects
				(font
					(size 1.27 1.27)
				)
				(hide yes)
			)
		)
		(property "MPN" "TPS65988DHRSHR "
			(at 71.12 36.83 0)
			(effects
				(font
					(size 1.27 1.27)
					(thickness 0.15)
				)
			)
		)
		(property "Manufacturer" "Texas Instruments"
			(at 102.87 57.15 0)
			(effects
				(font
					(size 1.27 1.27)
					(thickness 0.15)
				)
				(justify left bottom)
				(hide yes)
			)
		)
		(property "License" "Apache-2.0"
			(at 102.87 59.69 0)
			(effects
				(font
					(size 1.27 1.27)
					(thickness 0.15)
				)
				(justify left bottom)
				(hide yes)
			)
		)
		(property "Author" "Antmicro"
			(at 102.87 62.23 0)
			(effects
				(font
					(size 1.27 1.27)
					(thickness 0.15)
				)
				(justify left bottom)
				(hide yes)
			)
		)
		(pin "10"
		)
		(pin "16"
		)
		(pin "17"
		)
		(pin "18"
		)
		(pin "20"
		)
		(pin "21"
		)
		(pin "22"
		)
		(pin "23"
		)
		(pin "27"
		)
		(pin "28"
		)
		(pin "29"
		)
		(pin "30"
		)
		(pin "31"
		)
		(pin "32"
		)
		(pin "33"
		)
		(pin "34"
		)
		(pin "35"
		)
		(pin "36"
		)
		(pin "37"
		)
		(pin "38"
		)
		(pin "39"
		)
		(pin "40"
		)
		(pin "41"
		)
		(pin "42"
		)
		(pin "43"
		)
		(pin "44"
		)
		(pin "48"
		)
		(pin "49"
		)
		(pin "5"
		)
		(pin "51"
		)
		(pin "59"
		)
		(pin "6"
		)
		(pin "9"
		)
		(pin "11"
		)
		(pin "13"
		)
		(pin "15"
		)
		(pin "19"
		)
		(pin "24"
		)
		(pin "25"
		)
		(pin "26"
		)
		(pin "50"
		)
		(pin "53"
		)
		(pin "58"
		)
		(pin "8"
		)
		(pin "1"
		)
		(pin "3"
		)
		(pin "45"
		)
		(pin "46"
		)
		(pin "47"
		)
		(pin "52"
		)
		(pin "54"
		)
		(pin "55"
		)
		(pin "56"
		)
		(pin "57"
		)
		(pin "7"
		)
		(instances
			(project "jetson-orin-baseboard"
				(path ""
					(reference "U6")
					(unit 1)
				)
			)
		)
	)
	(symbol
		(lib_id "antmicroCapacitors0402:C_100n_0402")
		(at 190.5 67.31 90)
		(mirror x)
		(unit 1)
		(exclude_from_sim no)
		(in_bom yes)
		(on_board yes)
		(dnp no)
		(property "Reference" "C54"
			(at 192.405 68.58 90)
			(effects
				(font
					(size 1.27 1.27)
				)
				(justify right)
			)
		)
		(property "Value" "C_100n_0402"
			(at 200.66 87.63 0)
			(effects
				(font
					(size 1.27 1.27)
					(thickness 0.15)
				)
				(justify left bottom)
				(hide yes)
			)
		)
		(property "Footprint" "antmicro-footprints:C_0402_1005Metric"
			(at 203.2 87.63 0)
			(effects
				(font
					(size 1.27 1.27)
					(thickness 0.15)
				)
				(justify left bottom)
				(hide yes)
			)
		)
		(property "Datasheet" "https://www.murata.com/products/productdetail?partno=GRM155R61H104KE14%23"
			(at 205.74 87.63 0)
			(effects
				(font
					(size 1.27 1.27)
					(thickness 0.15)
				)
				(justify left bottom)
				(hide yes)
			)
		)
		(property "Description" ""
			(at 190.5 67.31 0)
			(effects
				(font
					(size 1.27 1.27)
				)
				(hide yes)
			)
		)
		(property "Manufacturer" "Murata"
			(at 210.82 87.63 0)
			(effects
				(font
					(size 1.27 1.27)
					(thickness 0.15)
				)
				(justify left bottom)
				(hide yes)
			)
		)
		(property "MPN" "GRM155R61H104KE14D"
			(at 208.28 87.63 0)
			(effects
				(font
					(size 1.27 1.27)
					(thickness 0.15)
				)
				(justify left bottom)
				(hide yes)
			)
		)
		(property "Val" "100n"
			(at 192.405 71.12 90)
			(effects
				(font
					(size 1.27 1.27)
					(thickness 0.15)
				)
				(justify right)
			)
		)
		(property "License" "Apache-2.0"
			(at 213.36 87.63 0)
			(effects
				(font
					(size 1.27 1.27)
					(thickness 0.15)
				)
				(justify left bottom)
				(hide yes)
			)
		)
		(property "Author" "Antmicro"
			(at 215.9 87.63 0)
			(effects
				(font
					(size 1.27 1.27)
					(thickness 0.15)
				)
				(justify left bottom)
				(hide yes)
			)
		)
		(property "Voltage" "50V"
			(at 218.44 87.63 0)
			(effects
				(font
					(size 1.27 1.27)
				)
				(justify left bottom)
				(hide yes)
			)
		)
		(property "Dielectric" "X5R"
			(at 220.98 87.63 0)
			(effects
				(font
					(size 1.27 1.27)
				)
				(justify left bottom)
				(hide yes)
			)
		)
		(pin "1"
		)
		(pin "2"
		)
		(instances
			(project "jetson-orin-baseboard"
				(path ""
					(reference "C54")
					(unit 1)
				)
			)
		)
	)
	(symbol
		(lib_name "GND_3")
		(lib_id "antmicropower:GND")
		(at 139.7 86.36 0)
		(mirror y)
		(unit 1)
		(exclude_from_sim no)
		(in_bom yes)
		(on_board yes)
		(dnp no)
		(property "Reference" "#PWR066"
			(at 139.7 92.71 0)
			(effects
				(font
					(size 1.27 1.27)
				)
				(justify left bottom)
				(hide yes)
			)
		)
		(property "Value" "GND"
			(at 139.7 90.17 0)
			(effects
				(font
					(size 1.27 1.27)
					(thickness 0.15)
				)
			)
		)
		(property "Footprint" ""
			(at 130.81 93.98 0)
			(effects
				(font
					(size 1.27 1.27)
					(thickness 0.15)
				)
				(justify left bottom)
				(hide yes)
			)
		)
		(property "Datasheet" ""
			(at 130.81 99.06 0)
			(effects
				(font
					(size 1.27 1.27)
					(thickness 0.15)
				)
				(justify left bottom)
				(hide yes)
			)
		)
		(property "Description" ""
			(at 139.7 86.36 0)
			(effects
				(font
					(size 1.27 1.27)
				)
				(hide yes)
			)
		)
		(property "Author" "Antmicro"
			(at 130.81 93.98 0)
			(effects
				(font
					(size 1.27 1.27)
					(thickness 0.15)
				)
				(justify left bottom)
				(hide yes)
			)
		)
		(property "License" "Apache-2.0"
			(at 130.81 96.52 0)
			(effects
				(font
					(size 1.27 1.27)
					(thickness 0.15)
				)
				(justify left bottom)
				(hide yes)
			)
		)
		(pin "1"
		)
		(instances
			(project "jetson-orin-baseboard"
				(path ""
					(reference "#PWR066")
					(unit 1)
				)
			)
		)
	)
	(symbol
		(lib_id "antmicroCapacitors0402:C_100n_0402")
		(at 168.91 67.31 90)
		(mirror x)
		(unit 1)
		(exclude_from_sim no)
		(in_bom yes)
		(on_board yes)
		(dnp no)
		(property "Reference" "C36"
			(at 170.815 68.58 90)
			(effects
				(font
					(size 1.27 1.27)
				)
				(justify right)
			)
		)
		(property "Value" "C_100n_0402"
			(at 179.07 87.63 0)
			(effects
				(font
					(size 1.27 1.27)
					(thickness 0.15)
				)
				(justify left bottom)
				(hide yes)
			)
		)
		(property "Footprint" "antmicro-footprints:C_0402_1005Metric"
			(at 181.61 87.63 0)
			(effects
				(font
					(size 1.27 1.27)
					(thickness 0.15)
				)
				(justify left bottom)
				(hide yes)
			)
		)
		(property "Datasheet" "https://www.murata.com/products/productdetail?partno=GRM155R61H104KE14%23"
			(at 184.15 87.63 0)
			(effects
				(font
					(size 1.27 1.27)
					(thickness 0.15)
				)
				(justify left bottom)
				(hide yes)
			)
		)
		(property "Description" ""
			(at 168.91 67.31 0)
			(effects
				(font
					(size 1.27 1.27)
				)
				(hide yes)
			)
		)
		(property "Manufacturer" "Murata"
			(at 189.23 87.63 0)
			(effects
				(font
					(size 1.27 1.27)
					(thickness 0.15)
				)
				(justify left bottom)
				(hide yes)
			)
		)
		(property "MPN" "GRM155R61H104KE14D"
			(at 186.69 87.63 0)
			(effects
				(font
					(size 1.27 1.27)
					(thickness 0.15)
				)
				(justify left bottom)
				(hide yes)
			)
		)
		(property "Val" "100n"
			(at 170.815 71.12 90)
			(effects
				(font
					(size 1.27 1.27)
					(thickness 0.15)
				)
				(justify right)
			)
		)
		(property "License" "Apache-2.0"
			(at 191.77 87.63 0)
			(effects
				(font
					(size 1.27 1.27)
					(thickness 0.15)
				)
				(justify left bottom)
				(hide yes)
			)
		)
		(property "Author" "Antmicro"
			(at 194.31 87.63 0)
			(effects
				(font
					(size 1.27 1.27)
					(thickness 0.15)
				)
				(justify left bottom)
				(hide yes)
			)
		)
		(property "Voltage" "50V"
			(at 196.85 87.63 0)
			(effects
				(font
					(size 1.27 1.27)
				)
				(justify left bottom)
				(hide yes)
			)
		)
		(property "Dielectric" "X5R"
			(at 199.39 87.63 0)
			(effects
				(font
					(size 1.27 1.27)
				)
				(justify left bottom)
				(hide yes)
			)
		)
		(pin "1"
		)
		(pin "2"
		)
		(instances
			(project "jetson-orin-baseboard"
				(path ""
					(reference "C36")
					(unit 1)
				)
			)
		)
	)
	(symbol
		(lib_id "antmicroTestPoints:TP_0.75mm_SMD")
		(at 363.22 190.5 0)
		(unit 1)
		(exclude_from_sim no)
		(in_bom no)
		(on_board yes)
		(dnp no)
		(property "Reference" "TP1"
			(at 367.03 190.5 0)
			(effects
				(font
					(size 1.27 1.27)
				)
				(justify left)
			)
		)
		(property "Value" "TP_0.75mm_SMD"
			(at 373.38 194.31 0)
			(effects
				(font
					(size 1.27 1.27)
					(thickness 0.15)
				)
				(justify left bottom)
				(hide yes)
			)
		)
		(property "Footprint" "antmicro-footprints:TP_SMD_0.75mm"
			(at 373.38 196.85 0)
			(effects
				(font
					(size 1.27 1.27)
					(thickness 0.15)
				)
				(justify left bottom)
				(hide yes)
			)
		)
		(property "Datasheet" ""
			(at 381 203.2 0)
			(effects
				(font
					(size 1.27 1.27)
					(thickness 0.15)
				)
				(justify left bottom)
				(hide yes)
			)
		)
		(property "Description" ""
			(at 363.22 190.5 0)
			(effects
				(font
					(size 1.27 1.27)
				)
				(hide yes)
			)
		)
		(property "MPN" ""
			(at 374.015 201.93 0)
			(effects
				(font
					(size 1.27 1.27)
					(thickness 0.15)
				)
				(justify left bottom)
				(hide yes)
			)
		)
		(property "Manufacturer" ""
			(at 374.015 196.85 0)
			(effects
				(font
					(size 1.27 1.27)
					(thickness 0.15)
				)
				(justify left bottom)
				(hide yes)
			)
		)
		(property "Author" "Antmicro"
			(at 373.38 199.39 0)
			(effects
				(font
					(size 1.27 1.27)
					(thickness 0.15)
				)
				(justify left bottom)
				(hide yes)
			)
		)
		(property "License" "Apache-2.0"
			(at 373.38 201.93 0)
			(effects
				(font
					(size 1.27 1.27)
					(thickness 0.15)
				)
				(justify left bottom)
				(hide yes)
			)
		)
		(pin "1"
		)
		(instances
			(project "jetson-orin-baseboard"
				(path ""
					(reference "TP1")
					(unit 1)
				)
			)
		)
	)
	(symbol
		(lib_name "TP_0.75mm_SMD_5")
		(lib_id "antmicroTestPoints:TP_0.75mm_SMD")
		(at 107.95 60.96 0)
		(unit 1)
		(exclude_from_sim no)
		(in_bom no)
		(on_board yes)
		(dnp no)
		(property "Reference" "TP26"
			(at 111.76 61.595 0)
			(effects
				(font
					(size 1.27 1.27)
				)
				(justify left bottom)
			)
		)
		(property "Value" "TP_0.75mm_SMD"
			(at 118.11 64.77 0)
			(effects
				(font
					(size 1.27 1.27)
					(thickness 0.15)
				)
				(justify left bottom)
				(hide yes)
			)
		)
		(property "Footprint" "antmicro-footprints:TP_SMD_0.75mm"
			(at 118.11 67.31 0)
			(effects
				(font
					(size 1.27 1.27)
					(thickness 0.15)
				)
				(justify left bottom)
				(hide yes)
			)
		)
		(property "Datasheet" ""
			(at 125.73 73.66 0)
			(effects
				(font
					(size 1.27 1.27)
					(thickness 0.15)
				)
				(justify left bottom)
				(hide yes)
			)
		)
		(property "Description" ""
			(at 107.95 60.96 0)
			(effects
				(font
					(size 1.27 1.27)
				)
				(hide yes)
			)
		)
		(property "MPN" ""
			(at 118.745 72.39 0)
			(effects
				(font
					(size 1.27 1.27)
					(thickness 0.15)
				)
				(justify left bottom)
				(hide yes)
			)
		)
		(property "Manufacturer" ""
			(at 118.745 67.31 0)
			(effects
				(font
					(size 1.27 1.27)
					(thickness 0.15)
				)
				(justify left bottom)
				(hide yes)
			)
		)
		(property "Author" "Antmicro"
			(at 118.11 69.85 0)
			(effects
				(font
					(size 1.27 1.27)
					(thickness 0.15)
				)
				(justify left bottom)
				(hide yes)
			)
		)
		(property "License" "Apache-2.0"
			(at 118.11 72.39 0)
			(effects
				(font
					(size 1.27 1.27)
					(thickness 0.15)
				)
				(justify left bottom)
				(hide yes)
			)
		)
		(pin "1"
		)
		(instances
			(project "jetson-orin-baseboard"
				(path ""
					(reference "TP26")
					(unit 1)
				)
			)
		)
	)
	(symbol
		(lib_name "TPD4E05U06QDQARQ1_1")
		(lib_id "antmicroTVSDiodes:TPD4E05U06QDQARQ1")
		(at 300.99 232.41 0)
		(unit 1)
		(exclude_from_sim no)
		(in_bom yes)
		(on_board yes)
		(dnp no)
		(fields_autoplaced yes)
		(property "Reference" "U11"
			(at 311.785 235.585 0)
			(effects
				(font
					(size 1.27 1.27)
				)
				(justify left)
			)
		)
		(property "Value" "TPD4E05U06QDQARQ1"
			(at 325.12 242.57 0)
			(effects
				(font
					(size 1.27 1.27)
					(thickness 0.15)
				)
				(justify left bottom)
				(hide yes)
			)
		)
		(property "Footprint" "antmicro-footprints:USON-10_2.5x1mm_P0.5mm"
			(at 325.12 237.49 0)
			(effects
				(font
					(size 1.27 1.27)
					(thickness 0.15)
				)
				(justify left bottom)
				(hide yes)
			)
		)
		(property "Datasheet" "https://www.ti.com/lit/ds/symlink/tpd4e05u06-q1.pdf?HQS=dis-mous-null-mousermode-dsf-pf-null-wwe&ts=1663591265741&ref_url=https%253A%252F%252Fwww.mouser.com%252F"
			(at 325.12 240.03 0)
			(effects
				(font
					(size 1.27 1.27)
					(thickness 0.15)
				)
				(justify left bottom)
				(hide yes)
			)
		)
		(property "Description" ""
			(at 300.99 232.41 0)
			(effects
				(font
					(size 1.27 1.27)
				)
				(hide yes)
			)
		)
		(property "Manufacturer" "Texas Instruments"
			(at 325.12 245.11 0)
			(effects
				(font
					(size 1.27 1.27)
					(thickness 0.15)
				)
				(justify left bottom)
				(hide yes)
			)
		)
		(property "MPN" "TPD4E05U06QDQARQ1"
			(at 311.785 238.125 0)
			(effects
				(font
					(size 1.27 1.27)
					(thickness 0.15)
				)
				(justify left)
			)
		)
		(property "Author" "Antmicro"
			(at 325.12 247.65 0)
			(effects
				(font
					(size 1.27 1.27)
					(thickness 0.15)
				)
				(justify left bottom)
				(hide yes)
			)
		)
		(property "License" "Apache-2.0"
			(at 325.12 250.19 0)
			(effects
				(font
					(size 1.27 1.27)
					(thickness 0.15)
				)
				(justify left bottom)
				(hide yes)
			)
		)
		(pin "1"
		)
		(pin "10"
		)
		(pin "2"
		)
		(pin "3"
		)
		(pin "4"
		)
		(pin "5"
		)
		(pin "6"
		)
		(pin "7"
		)
		(pin "8"
		)
		(pin "9"
		)
		(instances
			(project "jetson-orin-baseboard"
				(path ""
					(reference "U11")
					(unit 1)
				)
			)
		)
	)
	(symbol
		(lib_name "GND_3")
		(lib_id "antmicropower:GND")
		(at 170.18 156.21 0)
		(mirror y)
		(unit 1)
		(exclude_from_sim no)
		(in_bom yes)
		(on_board yes)
		(dnp no)
		(property "Reference" "#PWR010"
			(at 170.18 162.56 0)
			(effects
				(font
					(size 1.27 1.27)
				)
				(justify left bottom)
				(hide yes)
			)
		)
		(property "Value" "GND"
			(at 170.18 160.02 0)
			(effects
				(font
					(size 1.27 1.27)
					(thickness 0.15)
				)
			)
		)
		(property "Footprint" ""
			(at 161.29 163.83 0)
			(effects
				(font
					(size 1.27 1.27)
					(thickness 0.15)
				)
				(justify left bottom)
				(hide yes)
			)
		)
		(property "Datasheet" ""
			(at 161.29 168.91 0)
			(effects
				(font
					(size 1.27 1.27)
					(thickness 0.15)
				)
				(justify left bottom)
				(hide yes)
			)
		)
		(property "Description" ""
			(at 170.18 156.21 0)
			(effects
				(font
					(size 1.27 1.27)
				)
				(hide yes)
			)
		)
		(property "Author" "Antmicro"
			(at 161.29 163.83 0)
			(effects
				(font
					(size 1.27 1.27)
					(thickness 0.15)
				)
				(justify left bottom)
				(hide yes)
			)
		)
		(property "License" "Apache-2.0"
			(at 161.29 166.37 0)
			(effects
				(font
					(size 1.27 1.27)
					(thickness 0.15)
				)
				(justify left bottom)
				(hide yes)
			)
		)
		(pin "1"
		)
		(instances
			(project "jetson-orin-baseboard"
				(path ""
					(reference "#PWR010")
					(unit 1)
				)
			)
		)
	)
	(symbol
		(lib_name "GND_3")
		(lib_id "antmicropower:GND")
		(at 16.51 46.99 0)
		(mirror y)
		(unit 1)
		(exclude_from_sim no)
		(in_bom yes)
		(on_board yes)
		(dnp no)
		(property "Reference" "#PWR047"
			(at 16.51 53.34 0)
			(effects
				(font
					(size 1.27 1.27)
				)
				(justify left bottom)
				(hide yes)
			)
		)
		(property "Value" "GND"
			(at 16.51 50.8 0)
			(effects
				(font
					(size 1.27 1.27)
					(thickness 0.15)
				)
			)
		)
		(property "Footprint" ""
			(at 7.62 54.61 0)
			(effects
				(font
					(size 1.27 1.27)
					(thickness 0.15)
				)
				(justify left bottom)
				(hide yes)
			)
		)
		(property "Datasheet" ""
			(at 7.62 59.69 0)
			(effects
				(font
					(size 1.27 1.27)
					(thickness 0.15)
				)
				(justify left bottom)
				(hide yes)
			)
		)
		(property "Description" ""
			(at 16.51 46.99 0)
			(effects
				(font
					(size 1.27 1.27)
				)
				(hide yes)
			)
		)
		(property "Author" "Antmicro"
			(at 7.62 54.61 0)
			(effects
				(font
					(size 1.27 1.27)
					(thickness 0.15)
				)
				(justify left bottom)
				(hide yes)
			)
		)
		(property "License" "Apache-2.0"
			(at 7.62 57.15 0)
			(effects
				(font
					(size 1.27 1.27)
					(thickness 0.15)
				)
				(justify left bottom)
				(hide yes)
			)
		)
		(pin "1"
		)
		(instances
			(project "jetson-orin-baseboard"
				(path ""
					(reference "#PWR047")
					(unit 1)
				)
			)
		)
	)
	(symbol
		(lib_name "TP_0.75mm_SMD_6")
		(lib_id "antmicroTestPoints:TP_0.75mm_SMD")
		(at 105.41 109.22 0)
		(unit 1)
		(exclude_from_sim no)
		(in_bom no)
		(on_board yes)
		(dnp no)
		(property "Reference" "TP20"
			(at 109.22 109.855 0)
			(effects
				(font
					(size 1.27 1.27)
				)
				(justify left bottom)
			)
		)
		(property "Value" "TP_0.75mm_SMD"
			(at 115.57 113.03 0)
			(effects
				(font
					(size 1.27 1.27)
					(thickness 0.15)
				)
				(justify left bottom)
				(hide yes)
			)
		)
		(property "Footprint" "antmicro-footprints:TP_SMD_0.75mm"
			(at 115.57 115.57 0)
			(effects
				(font
					(size 1.27 1.27)
					(thickness 0.15)
				)
				(justify left bottom)
				(hide yes)
			)
		)
		(property "Datasheet" ""
			(at 123.19 121.92 0)
			(effects
				(font
					(size 1.27 1.27)
					(thickness 0.15)
				)
				(justify left bottom)
				(hide yes)
			)
		)
		(property "Description" ""
			(at 105.41 109.22 0)
			(effects
				(font
					(size 1.27 1.27)
				)
				(hide yes)
			)
		)
		(property "MPN" ""
			(at 116.205 120.65 0)
			(effects
				(font
					(size 1.27 1.27)
					(thickness 0.15)
				)
				(justify left bottom)
				(hide yes)
			)
		)
		(property "Manufacturer" ""
			(at 116.205 115.57 0)
			(effects
				(font
					(size 1.27 1.27)
					(thickness 0.15)
				)
				(justify left bottom)
				(hide yes)
			)
		)
		(property "Author" "Antmicro"
			(at 115.57 118.11 0)
			(effects
				(font
					(size 1.27 1.27)
					(thickness 0.15)
				)
				(justify left bottom)
				(hide yes)
			)
		)
		(property "License" "Apache-2.0"
			(at 115.57 120.65 0)
			(effects
				(font
					(size 1.27 1.27)
					(thickness 0.15)
				)
				(justify left bottom)
				(hide yes)
			)
		)
		(pin "1"
		)
		(instances
			(project "jetson-orin-baseboard"
				(path ""
					(reference "TP20")
					(unit 1)
				)
			)
		)
	)
	(symbol
		(lib_id "antmicroResistors0402:R_2M_0402")
		(at 359.41 133.35 270)
		(unit 1)
		(exclude_from_sim no)
		(in_bom yes)
		(on_board yes)
		(dnp no)
		(property "Reference" "R109"
			(at 358.14 134.62 90)
			(effects
				(font
					(size 1.27 1.27)
					(thickness 0.15)
				)
				(justify right)
			)
		)
		(property "Value" "R_2M_0402"
			(at 346.71 153.67 0)
			(effects
				(font
					(size 1.27 1.27)
					(thickness 0.15)
				)
				(justify left bottom)
				(hide yes)
			)
		)
		(property "Footprint" "antmicro-footprints:R_0402_1005Metric"
			(at 344.17 153.67 0)
			(effects
				(font
					(size 1.27 1.27)
					(thickness 0.15)
				)
				(justify left bottom)
				(hide yes)
			)
		)
		(property "Datasheet" "https://www.mouser.com/datasheet/2/447/YAGEO_PYu_RC_Group_51_RoHS_L_12-3313492.pdf"
			(at 341.63 153.67 0)
			(effects
				(font
					(size 1.27 1.27)
					(thickness 0.15)
				)
				(justify left bottom)
				(hide yes)
			)
		)
		(property "Description" "SMD Chip Resistor, 2 Mohm, ± 1%, 62.5 mW, 0402 [1005 Metric], Thick Film, General Purpose"
			(at 359.41 133.35 0)
			(effects
				(font
					(size 1.27 1.27)
				)
				(hide yes)
			)
		)
		(property "MPN" "RC0402FR-072ML"
			(at 339.09 153.67 0)
			(effects
				(font
					(size 1.27 1.27)
					(thickness 0.15)
				)
				(justify left bottom)
				(hide yes)
			)
		)
		(property "Manufacturer" "YAGEO"
			(at 336.55 153.67 0)
			(effects
				(font
					(size 1.27 1.27)
					(thickness 0.15)
				)
				(justify left bottom)
				(hide yes)
			)
		)
		(property "License" "Apache-2.0"
			(at 334.01 153.67 0)
			(effects
				(font
					(size 1.27 1.27)
					(thickness 0.15)
				)
				(justify left bottom)
				(hide yes)
			)
		)
		(property "Author" "Antmicro"
			(at 331.47 153.67 0)
			(effects
				(font
					(size 1.27 1.27)
					(thickness 0.15)
				)
				(justify left bottom)
				(hide yes)
			)
		)
		(property "Val" "2M"
			(at 358.14 137.16 90)
			(effects
				(font
					(size 1.27 1.27)
					(thickness 0.15)
				)
				(justify right)
			)
		)
		(property "Tolerance" "1%"
			(at 349.25 153.67 0)
			(effects
				(font
					(size 1.27 1.27)
				)
				(justify left bottom)
				(hide yes)
			)
		)
		(pin "1"
		)
		(pin "2"
		)
		(instances
			(project "jetson-orin-baseboard"
				(path ""
					(reference "R109")
					(unit 1)
				)
			)
		)
	)
	(symbol
		(lib_name "GND_3")
		(lib_id "antmicropower:GND")
		(at 35.56 200.66 0)
		(mirror y)
		(unit 1)
		(exclude_from_sim no)
		(in_bom yes)
		(on_board yes)
		(dnp no)
		(property "Reference" "#PWR053"
			(at 35.56 207.01 0)
			(effects
				(font
					(size 1.27 1.27)
				)
				(justify left bottom)
				(hide yes)
			)
		)
		(property "Value" "GND"
			(at 35.56 204.47 0)
			(effects
				(font
					(size 1.27 1.27)
					(thickness 0.15)
				)
			)
		)
		(property "Footprint" ""
			(at 26.67 208.28 0)
			(effects
				(font
					(size 1.27 1.27)
					(thickness 0.15)
				)
				(justify left bottom)
				(hide yes)
			)
		)
		(property "Datasheet" ""
			(at 26.67 213.36 0)
			(effects
				(font
					(size 1.27 1.27)
					(thickness 0.15)
				)
				(justify left bottom)
				(hide yes)
			)
		)
		(property "Description" ""
			(at 35.56 200.66 0)
			(effects
				(font
					(size 1.27 1.27)
				)
				(hide yes)
			)
		)
		(property "Author" "Antmicro"
			(at 26.67 208.28 0)
			(effects
				(font
					(size 1.27 1.27)
					(thickness 0.15)
				)
				(justify left bottom)
				(hide yes)
			)
		)
		(property "License" "Apache-2.0"
			(at 26.67 210.82 0)
			(effects
				(font
					(size 1.27 1.27)
					(thickness 0.15)
				)
				(justify left bottom)
				(hide yes)
			)
		)
		(pin "1"
		)
		(instances
			(project "jetson-orin-baseboard"
				(path ""
					(reference "#PWR053")
					(unit 1)
				)
			)
		)
	)
	(symbol
		(lib_id "antmicroResistors0402:R_0R_0402")
		(at 187.96 172.72 0)
		(mirror x)
		(unit 1)
		(exclude_from_sim no)
		(in_bom yes)
		(on_board yes)
		(dnp no)
		(property "Reference" "R75"
			(at 193.04 172.085 0)
			(effects
				(font
					(size 1.27 1.27)
				)
				(justify left top)
			)
		)
		(property "Value" "R_0R_0402"
			(at 208.28 160.02 0)
			(effects
				(font
					(size 1.27 1.27)
					(thickness 0.15)
				)
				(justify left bottom)
				(hide yes)
			)
		)
		(property "Footprint" "antmicro-footprints:R_0402_1005Metric"
			(at 208.28 157.48 0)
			(effects
				(font
					(size 1.27 1.27)
					(thickness 0.15)
				)
				(justify left bottom)
				(hide yes)
			)
		)
		(property "Datasheet" "https://industrial.panasonic.com/cdbs/www-data/pdf/RDA0000/AOA0000C301.pdf"
			(at 208.28 154.94 0)
			(effects
				(font
					(size 1.27 1.27)
					(thickness 0.15)
				)
				(justify left bottom)
				(hide yes)
			)
		)
		(property "Description" ""
			(at 187.96 172.72 0)
			(effects
				(font
					(size 1.27 1.27)
				)
				(hide yes)
			)
		)
		(property "Manufacturer" "Panasonic"
			(at 208.28 149.86 0)
			(effects
				(font
					(size 1.27 1.27)
					(thickness 0.15)
				)
				(justify left bottom)
				(hide yes)
			)
		)
		(property "MPN" "ERJ2GE0R00X"
			(at 208.28 152.4 0)
			(effects
				(font
					(size 1.27 1.27)
					(thickness 0.15)
				)
				(justify left bottom)
				(hide yes)
			)
		)
		(property "Val" "0R"
			(at 185.42 172.085 0)
			(effects
				(font
					(size 1.27 1.27)
					(thickness 0.15)
				)
				(justify left top)
			)
		)
		(property "License" "Apache-2.0"
			(at 208.28 147.32 0)
			(effects
				(font
					(size 1.27 1.27)
					(thickness 0.15)
				)
				(justify left bottom)
				(hide yes)
			)
		)
		(property "Author" "Antmicro"
			(at 208.28 144.78 0)
			(effects
				(font
					(size 1.27 1.27)
					(thickness 0.15)
				)
				(justify left bottom)
				(hide yes)
			)
		)
		(property "Tolerance" "~"
			(at 208.28 162.56 0)
			(effects
				(font
					(size 1.27 1.27)
				)
				(justify left bottom)
				(hide yes)
			)
		)
		(property "Current" "1A"
			(at 208.28 142.24 0)
			(effects
				(font
					(size 1.27 1.27)
					(thickness 0.15)
				)
				(justify left bottom)
				(hide yes)
			)
		)
		(pin "1"
		)
		(pin "2"
		)
		(instances
			(project "jetson-orin-baseboard"
				(path ""
					(reference "R75")
					(unit 1)
				)
			)
		)
	)
	(symbol
		(lib_name "C_100n_0402_7")
		(lib_id "antmicroCapacitors0402:C_100n_0402")
		(at 111.76 271.78 90)
		(mirror x)
		(unit 1)
		(exclude_from_sim no)
		(in_bom yes)
		(on_board yes)
		(dnp no)
		(fields_autoplaced yes)
		(property "Reference" "C158"
			(at 109.22 273.0563 90)
			(effects
				(font
					(size 1.27 1.27)
				)
				(justify left)
			)
		)
		(property "Value" "C_100n_0402"
			(at 121.92 292.1 0)
			(effects
				(font
					(size 1.27 1.27)
					(thickness 0.15)
				)
				(justify left bottom)
				(hide yes)
			)
		)
		(property "Footprint" "antmicro-footprints:C_0402_1005Metric"
			(at 124.46 292.1 0)
			(effects
				(font
					(size 1.27 1.27)
					(thickness 0.15)
				)
				(justify left bottom)
				(hide yes)
			)
		)
		(property "Datasheet" "https://www.murata.com/products/productdetail?partno=GRM155R61H104KE14%23"
			(at 127 292.1 0)
			(effects
				(font
					(size 1.27 1.27)
					(thickness 0.15)
				)
				(justify left bottom)
				(hide yes)
			)
		)
		(property "Description" ""
			(at 111.76 271.78 0)
			(effects
				(font
					(size 1.27 1.27)
				)
				(hide yes)
			)
		)
		(property "MPN" "GRM155R61H104KE14D"
			(at 129.54 292.1 0)
			(effects
				(font
					(size 1.27 1.27)
					(thickness 0.15)
				)
				(justify left bottom)
				(hide yes)
			)
		)
		(property "Manufacturer" "Murata"
			(at 132.08 292.1 0)
			(effects
				(font
					(size 1.27 1.27)
					(thickness 0.15)
				)
				(justify left bottom)
				(hide yes)
			)
		)
		(property "Val" "100n"
			(at 109.22 275.5963 90)
			(effects
				(font
					(size 1.27 1.27)
					(thickness 0.15)
				)
				(justify left)
			)
		)
		(property "License" "Apache-2.0"
			(at 134.62 292.1 0)
			(effects
				(font
					(size 1.27 1.27)
					(thickness 0.15)
				)
				(justify left bottom)
				(hide yes)
			)
		)
		(property "Author" "Antmicro"
			(at 137.16 292.1 0)
			(effects
				(font
					(size 1.27 1.27)
					(thickness 0.15)
				)
				(justify left bottom)
				(hide yes)
			)
		)
		(property "Voltage" "50V"
			(at 139.7 292.1 0)
			(effects
				(font
					(size 1.27 1.27)
				)
				(justify left bottom)
				(hide yes)
			)
		)
		(property "Dielectric" "X5R"
			(at 142.24 292.1 0)
			(effects
				(font
					(size 1.27 1.27)
				)
				(justify left bottom)
				(hide yes)
			)
		)
		(pin "1"
		)
		(pin "2"
		)
		(instances
			(project "jetson-orin-baseboard"
				(path ""
					(reference "C158")
					(unit 1)
				)
			)
		)
	)
	(symbol
		(lib_id "antmicroCapacitors0402:C_10u_0402")
		(at 33.02 45.72 90)
		(unit 1)
		(exclude_from_sim no)
		(in_bom yes)
		(on_board yes)
		(dnp no)
		(property "Reference" "C30"
			(at 33.655 41.275 90)
			(effects
				(font
					(size 1.27 1.27)
					(thickness 0.15)
				)
				(justify right)
			)
		)
		(property "Value" "C_10u_0402"
			(at 43.18 25.4 0)
			(effects
				(font
					(size 1.27 1.27)
					(thickness 0.15)
				)
				(justify left bottom)
				(hide yes)
			)
		)
		(property "Footprint" "antmicro-footprints:C_0402_1005Metric"
			(at 45.72 25.4 0)
			(effects
				(font
					(size 1.27 1.27)
					(thickness 0.15)
				)
				(justify left bottom)
				(hide yes)
			)
		)
		(property "Datasheet" "https://www.yageo.com/en/Chart/Download/pdf/CC0402MRX5R5BB106"
			(at 48.26 25.4 0)
			(effects
				(font
					(size 1.27 1.27)
					(thickness 0.15)
				)
				(justify left bottom)
				(hide yes)
			)
		)
		(property "Description" ""
			(at 33.02 45.72 0)
			(effects
				(font
					(size 1.27 1.27)
				)
				(hide yes)
			)
		)
		(property "MPN" "CC0402MRX5R5BB106"
			(at 50.8 25.4 0)
			(effects
				(font
					(size 1.27 1.27)
					(thickness 0.15)
				)
				(justify left bottom)
				(hide yes)
			)
		)
		(property "Manufacturer" "YAGEO"
			(at 53.34 25.4 0)
			(effects
				(font
					(size 1.27 1.27)
					(thickness 0.15)
				)
				(justify left bottom)
				(hide yes)
			)
		)
		(property "License" "Apache-2.0"
			(at 55.88 25.4 0)
			(effects
				(font
					(size 1.27 1.27)
					(thickness 0.15)
				)
				(justify left bottom)
				(hide yes)
			)
		)
		(property "Author" "Antmicro"
			(at 58.42 25.4 0)
			(effects
				(font
					(size 1.27 1.27)
					(thickness 0.15)
				)
				(justify left bottom)
				(hide yes)
			)
		)
		(property "Val" "10u"
			(at 33.655 45.085 90)
			(effects
				(font
					(size 1.27 1.27)
					(thickness 0.15)
				)
				(justify right)
			)
		)
		(property "Voltage" ""
			(at 60.96 25.4 0)
			(effects
				(font
					(size 1.27 1.27)
				)
				(justify left bottom)
				(hide yes)
			)
		)
		(property "Dielectric" ""
			(at 63.5 25.4 0)
			(effects
				(font
					(size 1.27 1.27)
				)
				(justify left bottom)
				(hide yes)
			)
		)
		(pin "1"
		)
		(pin "2"
		)
		(instances
			(project "jetson-orin-baseboard"
				(path ""
					(reference "C30")
					(unit 1)
				)
			)
		)
	)
	(symbol
		(lib_name "GND_3")
		(lib_id "antmicropower:GND")
		(at 21.59 46.99 0)
		(mirror y)
		(unit 1)
		(exclude_from_sim no)
		(in_bom yes)
		(on_board yes)
		(dnp no)
		(property "Reference" "#PWR049"
			(at 21.59 53.34 0)
			(effects
				(font
					(size 1.27 1.27)
				)
				(justify left bottom)
				(hide yes)
			)
		)
		(property "Value" "GND"
			(at 21.59 50.8 0)
			(effects
				(font
					(size 1.27 1.27)
					(thickness 0.15)
				)
			)
		)
		(property "Footprint" ""
			(at 12.7 54.61 0)
			(effects
				(font
					(size 1.27 1.27)
					(thickness 0.15)
				)
				(justify left bottom)
				(hide yes)
			)
		)
		(property "Datasheet" ""
			(at 12.7 59.69 0)
			(effects
				(font
					(size 1.27 1.27)
					(thickness 0.15)
				)
				(justify left bottom)
				(hide yes)
			)
		)
		(property "Description" ""
			(at 21.59 46.99 0)
			(effects
				(font
					(size 1.27 1.27)
				)
				(hide yes)
			)
		)
		(property "Author" "Antmicro"
			(at 12.7 54.61 0)
			(effects
				(font
					(size 1.27 1.27)
					(thickness 0.15)
				)
				(justify left bottom)
				(hide yes)
			)
		)
		(property "License" "Apache-2.0"
			(at 12.7 57.15 0)
			(effects
				(font
					(size 1.27 1.27)
					(thickness 0.15)
				)
				(justify left bottom)
				(hide yes)
			)
		)
		(pin "1"
		)
		(instances
			(project "jetson-orin-baseboard"
				(path ""
					(reference "#PWR049")
					(unit 1)
				)
			)
		)
	)
	(symbol
		(lib_id "antmicroCapacitors0402:C_10u_0402")
		(at 157.48 72.39 90)
		(unit 1)
		(exclude_from_sim no)
		(in_bom yes)
		(on_board yes)
		(dnp no)
		(fields_autoplaced yes)
		(property "Reference" "C56"
			(at 160.655 68.5736 90)
			(effects
				(font
					(size 1.27 1.27)
					(thickness 0.15)
				)
				(justify right)
			)
		)
		(property "Value" "C_10u_0402"
			(at 167.64 52.07 0)
			(effects
				(font
					(size 1.27 1.27)
					(thickness 0.15)
				)
				(justify left bottom)
				(hide yes)
			)
		)
		(property "Footprint" "antmicro-footprints:C_0402_1005Metric"
			(at 170.18 52.07 0)
			(effects
				(font
					(size 1.27 1.27)
					(thickness 0.15)
				)
				(justify left bottom)
				(hide yes)
			)
		)
		(property "Datasheet" "https://www.yageo.com/en/Chart/Download/pdf/CC0402MRX5R5BB106"
			(at 172.72 52.07 0)
			(effects
				(font
					(size 1.27 1.27)
					(thickness 0.15)
				)
				(justify left bottom)
				(hide yes)
			)
		)
		(property "Description" ""
			(at 157.48 72.39 0)
			(effects
				(font
					(size 1.27 1.27)
				)
				(hide yes)
			)
		)
		(property "MPN" "CC0402MRX5R5BB106"
			(at 175.26 52.07 0)
			(effects
				(font
					(size 1.27 1.27)
					(thickness 0.15)
				)
				(justify left bottom)
				(hide yes)
			)
		)
		(property "Manufacturer" "YAGEO"
			(at 177.8 52.07 0)
			(effects
				(font
					(size 1.27 1.27)
					(thickness 0.15)
				)
				(justify left bottom)
				(hide yes)
			)
		)
		(property "License" "Apache-2.0"
			(at 180.34 52.07 0)
			(effects
				(font
					(size 1.27 1.27)
					(thickness 0.15)
				)
				(justify left bottom)
				(hide yes)
			)
		)
		(property "Author" "Antmicro"
			(at 182.88 52.07 0)
			(effects
				(font
					(size 1.27 1.27)
					(thickness 0.15)
				)
				(justify left bottom)
				(hide yes)
			)
		)
		(property "Val" "10u"
			(at 160.655 71.1136 90)
			(effects
				(font
					(size 1.27 1.27)
					(thickness 0.15)
				)
				(justify right)
			)
		)
		(property "Voltage" ""
			(at 185.42 52.07 0)
			(effects
				(font
					(size 1.27 1.27)
				)
				(justify left bottom)
				(hide yes)
			)
		)
		(property "Dielectric" ""
			(at 187.96 52.07 0)
			(effects
				(font
					(size 1.27 1.27)
				)
				(justify left bottom)
				(hide yes)
			)
		)
		(pin "1"
		)
		(pin "2"
		)
		(instances
			(project "jetson-orin-baseboard"
				(path ""
					(reference "C56")
					(unit 1)
				)
			)
		)
	)
	(symbol
		(lib_name "GND_3")
		(lib_id "antmicropower:GND")
		(at 129.54 278.13 0)
		(unit 1)
		(exclude_from_sim no)
		(in_bom yes)
		(on_board yes)
		(dnp no)
		(property "Reference" "#PWR0360"
			(at 129.54 284.48 0)
			(effects
				(font
					(size 1.27 1.27)
				)
				(justify left bottom)
				(hide yes)
			)
		)
		(property "Value" "GND"
			(at 129.54 281.94 0)
			(effects
				(font
					(size 1.27 1.27)
					(thickness 0.15)
				)
			)
		)
		(property "Footprint" ""
			(at 138.43 285.75 0)
			(effects
				(font
					(size 1.27 1.27)
					(thickness 0.15)
				)
				(justify left bottom)
				(hide yes)
			)
		)
		(property "Datasheet" ""
			(at 138.43 290.83 0)
			(effects
				(font
					(size 1.27 1.27)
					(thickness 0.15)
				)
				(justify left bottom)
				(hide yes)
			)
		)
		(property "Description" ""
			(at 129.54 278.13 0)
			(effects
				(font
					(size 1.27 1.27)
				)
				(hide yes)
			)
		)
		(property "Author" "Antmicro"
			(at 138.43 285.75 0)
			(effects
				(font
					(size 1.27 1.27)
					(thickness 0.15)
				)
				(justify left bottom)
				(hide yes)
			)
		)
		(property "License" "Apache-2.0"
			(at 138.43 288.29 0)
			(effects
				(font
					(size 1.27 1.27)
					(thickness 0.15)
				)
				(justify left bottom)
				(hide yes)
			)
		)
		(pin "1"
		)
		(instances
			(project "jetson-orin-baseboard"
				(path ""
					(reference "#PWR0360")
					(unit 1)
				)
			)
		)
	)
	(symbol
		(lib_name "R_0R_0402_4")
		(lib_id "antmicroResistors0402:R_0R_0402")
		(at 30.48 55.88 0)
		(unit 1)
		(exclude_from_sim no)
		(in_bom yes)
		(on_board yes)
		(dnp no)
		(property "Reference" "R41"
			(at 35.56 55.245 0)
			(effects
				(font
					(size 1.27 1.27)
				)
				(justify left bottom)
			)
		)
		(property "Value" "R_0R_0402"
			(at 50.8 68.58 0)
			(effects
				(font
					(size 1.27 1.27)
					(thickness 0.15)
				)
				(justify left bottom)
				(hide yes)
			)
		)
		(property "Footprint" "antmicro-footprints:R_0402_1005Metric"
			(at 50.8 71.12 0)
			(effects
				(font
					(size 1.27 1.27)
					(thickness 0.15)
				)
				(justify left bottom)
				(hide yes)
			)
		)
		(property "Datasheet" "https://industrial.panasonic.com/cdbs/www-data/pdf/RDA0000/AOA0000C301.pdf"
			(at 50.8 73.66 0)
			(effects
				(font
					(size 1.27 1.27)
					(thickness 0.15)
				)
				(justify left bottom)
				(hide yes)
			)
		)
		(property "Description" ""
			(at 30.48 55.88 0)
			(effects
				(font
					(size 1.27 1.27)
				)
				(hide yes)
			)
		)
		(property "Manufacturer" "Panasonic"
			(at 50.8 78.74 0)
			(effects
				(font
					(size 1.27 1.27)
					(thickness 0.15)
				)
				(justify left bottom)
				(hide yes)
			)
		)
		(property "MPN" "ERJ2GE0R00X"
			(at 50.8 76.2 0)
			(effects
				(font
					(size 1.27 1.27)
					(thickness 0.15)
				)
				(justify left bottom)
				(hide yes)
			)
		)
		(property "Val" "0R"
			(at 27.94 55.245 0)
			(effects
				(font
					(size 1.27 1.27)
					(thickness 0.15)
				)
				(justify left bottom)
			)
		)
		(property "License" "Apache-2.0"
			(at 50.8 81.28 0)
			(effects
				(font
					(size 1.27 1.27)
					(thickness 0.15)
				)
				(justify left bottom)
				(hide yes)
			)
		)
		(property "Author" "Antmicro"
			(at 50.8 83.82 0)
			(effects
				(font
					(size 1.27 1.27)
					(thickness 0.15)
				)
				(justify left bottom)
				(hide yes)
			)
		)
		(property "Tolerance" "~"
			(at 50.8 66.04 0)
			(effects
				(font
					(size 1.27 1.27)
				)
				(justify left bottom)
				(hide yes)
			)
		)
		(property "Current" "1A"
			(at 50.8 86.36 0)
			(effects
				(font
					(size 1.27 1.27)
					(thickness 0.15)
				)
				(justify left bottom)
				(hide yes)
			)
		)
		(pin "1"
		)
		(pin "2"
		)
		(instances
			(project "jetson-orin-baseboard"
				(path ""
					(reference "R41")
					(unit 1)
				)
			)
		)
	)
	(symbol
		(lib_id "antmicroResistors0402:R_1k_0402")
		(at 262.89 142.24 0)
		(unit 1)
		(exclude_from_sim no)
		(in_bom yes)
		(on_board yes)
		(dnp no)
		(property "Reference" "R86"
			(at 268.605 141.605 0)
			(effects
				(font
					(size 1.27 1.27)
				)
				(justify left bottom)
			)
		)
		(property "Value" "R_1k_0402"
			(at 283.21 154.94 0)
			(effects
				(font
					(size 1.27 1.27)
					(thickness 0.15)
				)
				(justify left bottom)
				(hide yes)
			)
		)
		(property "Footprint" "antmicro-footprints:R_0402_1005Metric"
			(at 283.21 157.48 0)
			(effects
				(font
					(size 1.27 1.27)
					(thickness 0.15)
				)
				(justify left bottom)
				(hide yes)
			)
		)
		(property "Datasheet" "https://www.bourns.com/docs/product-datasheets/cr.pdf"
			(at 283.21 160.02 0)
			(effects
				(font
					(size 1.27 1.27)
					(thickness 0.15)
				)
				(justify left bottom)
				(hide yes)
			)
		)
		(property "Description" ""
			(at 262.89 142.24 0)
			(effects
				(font
					(size 1.27 1.27)
				)
				(hide yes)
			)
		)
		(property "Manufacturer" "Bourns"
			(at 283.21 165.1 0)
			(effects
				(font
					(size 1.27 1.27)
					(thickness 0.15)
				)
				(justify left bottom)
				(hide yes)
			)
		)
		(property "MPN" "CR0402-FX-1001GLF"
			(at 283.21 162.56 0)
			(effects
				(font
					(size 1.27 1.27)
					(thickness 0.15)
				)
				(justify left bottom)
				(hide yes)
			)
		)
		(property "Val" "1k"
			(at 260.35 141.605 0)
			(effects
				(font
					(size 1.27 1.27)
					(thickness 0.15)
				)
				(justify left bottom)
			)
		)
		(property "License" "Apache-2.0"
			(at 283.21 167.64 0)
			(effects
				(font
					(size 1.27 1.27)
					(thickness 0.15)
				)
				(justify left bottom)
				(hide yes)
			)
		)
		(property "Author" "Antmicro"
			(at 283.21 170.18 0)
			(effects
				(font
					(size 1.27 1.27)
					(thickness 0.15)
				)
				(justify left bottom)
				(hide yes)
			)
		)
		(property "Tolerance" "1%"
			(at 283.21 152.4 0)
			(effects
				(font
					(size 1.27 1.27)
				)
				(justify left bottom)
				(hide yes)
			)
		)
		(pin "1"
		)
		(pin "2"
		)
		(instances
			(project "jetson-orin-baseboard"
				(path ""
					(reference "R86")
					(unit 1)
				)
			)
		)
	)
	(symbol
		(lib_name "GND_3")
		(lib_id "antmicropower:GND")
		(at 360.68 48.26 0)
		(mirror y)
		(unit 1)
		(exclude_from_sim no)
		(in_bom yes)
		(on_board yes)
		(dnp no)
		(property "Reference" "#PWR097"
			(at 360.68 54.61 0)
			(effects
				(font
					(size 1.27 1.27)
				)
				(justify left bottom)
				(hide yes)
			)
		)
		(property "Value" "GND"
			(at 360.68 52.07 0)
			(effects
				(font
					(size 1.27 1.27)
					(thickness 0.15)
				)
			)
		)
		(property "Footprint" ""
			(at 351.79 55.88 0)
			(effects
				(font
					(size 1.27 1.27)
					(thickness 0.15)
				)
				(justify left bottom)
				(hide yes)
			)
		)
		(property "Datasheet" ""
			(at 351.79 60.96 0)
			(effects
				(font
					(size 1.27 1.27)
					(thickness 0.15)
				)
				(justify left bottom)
				(hide yes)
			)
		)
		(property "Description" ""
			(at 360.68 48.26 0)
			(effects
				(font
					(size 1.27 1.27)
				)
				(hide yes)
			)
		)
		(property "Author" "Antmicro"
			(at 351.79 55.88 0)
			(effects
				(font
					(size 1.27 1.27)
					(thickness 0.15)
				)
				(justify left bottom)
				(hide yes)
			)
		)
		(property "License" "Apache-2.0"
			(at 351.79 58.42 0)
			(effects
				(font
					(size 1.27 1.27)
					(thickness 0.15)
				)
				(justify left bottom)
				(hide yes)
			)
		)
		(pin "1"
		)
		(instances
			(project "jetson-orin-baseboard"
				(path ""
					(reference "#PWR097")
					(unit 1)
				)
			)
		)
	)
	(symbol
		(lib_id "antmicroTransistorsFETsMOSFETsSingle:PJE138K")
		(at 55.88 259.08 0)
		(unit 1)
		(exclude_from_sim no)
		(in_bom yes)
		(on_board yes)
		(dnp no)
		(fields_autoplaced yes)
		(property "Reference" "Q21"
			(at 66.04 255.27 0)
			(effects
				(font
					(size 1.27 1.27)
					(thickness 0.15)
				)
				(justify left)
			)
		)
		(property "Value" "PJE138K"
			(at 78.74 267.97 0)
			(effects
				(font
					(size 1.27 1.27)
					(thickness 0.15)
				)
				(justify left bottom)
				(hide yes)
			)
		)
		(property "Footprint" "antmicro-footprints:SOT-523"
			(at 78.74 270.51 0)
			(effects
				(font
					(size 1.27 1.27)
					(thickness 0.15)
				)
				(justify left bottom)
				(hide yes)
			)
		)
		(property "Datasheet" "https://www.mouser.com/datasheet/2/1057/PJE138K-1876698.pdf"
			(at 78.74 273.05 0)
			(effects
				(font
					(size 1.27 1.27)
					(thickness 0.15)
				)
				(justify left bottom)
				(hide yes)
			)
		)
		(property "Description" ""
			(at 55.88 259.08 0)
			(effects
				(font
					(size 1.27 1.27)
				)
				(hide yes)
			)
		)
		(property "MPN" "PJE138K_R1_00001"
			(at 66.04 257.81 0)
			(effects
				(font
					(size 1.27 1.27)
					(thickness 0.15)
				)
				(justify left)
			)
		)
		(property "Manufacturer" "PANJIT"
			(at 78.74 278.13 0)
			(effects
				(font
					(size 1.27 1.27)
					(thickness 0.15)
				)
				(justify left bottom)
				(hide yes)
			)
		)
		(property "Author" "Antmicro"
			(at 78.74 280.67 0)
			(effects
				(font
					(size 1.27 1.27)
					(thickness 0.15)
				)
				(justify left bottom)
				(hide yes)
			)
		)
		(property "License" "Apache-2.0"
			(at 78.74 283.21 0)
			(effects
				(font
					(size 1.27 1.27)
					(thickness 0.15)
				)
				(justify left bottom)
				(hide yes)
			)
		)
		(pin "1"
		)
		(pin "2"
		)
		(pin "3"
		)
		(instances
			(project "jetson-orin-baseboard"
				(path ""
					(reference "Q21")
					(unit 1)
				)
			)
		)
	)
	(symbol
		(lib_id "antmicroResistors0402:R_10k_0402")
		(at 46.99 130.81 180)
		(unit 1)
		(exclude_from_sim no)
		(in_bom yes)
		(on_board yes)
		(dnp no)
		(property "Reference" "R131"
			(at 39.37 129.54 0)
			(effects
				(font
					(size 1.27 1.27)
					(thickness 0.15)
				)
			)
		)
		(property "Value" "R_10k_0402"
			(at 26.67 118.11 0)
			(effects
				(font
					(size 1.27 1.27)
					(thickness 0.15)
				)
				(justify left bottom)
				(hide yes)
			)
		)
		(property "Footprint" "antmicro-footprints:R_0402_1005Metric"
			(at 26.67 115.57 0)
			(effects
				(font
					(size 1.27 1.27)
					(thickness 0.15)
				)
				(justify left bottom)
				(hide yes)
			)
		)
		(property "Datasheet" "https://www.bourns.com/docs/product-datasheets/cr.pdf"
			(at 26.67 113.03 0)
			(effects
				(font
					(size 1.27 1.27)
					(thickness 0.15)
				)
				(justify left bottom)
				(hide yes)
			)
		)
		(property "Description" ""
			(at 46.99 130.81 0)
			(effects
				(font
					(size 1.27 1.27)
				)
				(hide yes)
			)
		)
		(property "MPN" "CR0402-FX-1002GLF"
			(at 26.67 110.49 0)
			(effects
				(font
					(size 1.27 1.27)
					(thickness 0.15)
				)
				(justify left bottom)
				(hide yes)
			)
		)
		(property "Manufacturer" "Bourns"
			(at 26.67 107.95 0)
			(effects
				(font
					(size 1.27 1.27)
					(thickness 0.15)
				)
				(justify left bottom)
				(hide yes)
			)
		)
		(property "License" "Apache-2.0"
			(at 26.67 105.41 0)
			(effects
				(font
					(size 1.27 1.27)
					(thickness 0.15)
				)
				(justify left bottom)
				(hide yes)
			)
		)
		(property "Author" "Antmicro"
			(at 26.67 102.87 0)
			(effects
				(font
					(size 1.27 1.27)
					(thickness 0.15)
				)
				(justify left bottom)
				(hide yes)
			)
		)
		(property "Val" "10k"
			(at 48.26 129.54 0)
			(effects
				(font
					(size 1.27 1.27)
					(thickness 0.15)
				)
			)
		)
		(property "Tolerance" "1%"
			(at 26.67 120.65 0)
			(effects
				(font
					(size 1.27 1.27)
				)
				(justify left bottom)
				(hide yes)
			)
		)
		(pin "1"
		)
		(pin "2"
		)
		(instances
			(project "jetson-orin-baseboard"
				(path ""
					(reference "R131")
					(unit 1)
				)
			)
		)
	)
	(symbol
		(lib_id "antmicroResistors0402:R_1k_0402")
		(at 262.89 167.64 0)
		(unit 1)
		(exclude_from_sim no)
		(in_bom no)
		(on_board yes)
		(dnp yes)
		(property "Reference" "R96"
			(at 268.605 167.005 0)
			(effects
				(font
					(size 1.27 1.27)
				)
				(justify left bottom)
			)
		)
		(property "Value" "R_1k_0402"
			(at 283.21 180.34 0)
			(effects
				(font
					(size 1.27 1.27)
					(thickness 0.15)
				)
				(justify left bottom)
				(hide yes)
			)
		)
		(property "Footprint" "antmicro-footprints:R_0402_1005Metric"
			(at 283.21 182.88 0)
			(effects
				(font
					(size 1.27 1.27)
					(thickness 0.15)
				)
				(justify left bottom)
				(hide yes)
			)
		)
		(property "Datasheet" "https://www.bourns.com/docs/product-datasheets/cr.pdf"
			(at 283.21 185.42 0)
			(effects
				(font
					(size 1.27 1.27)
					(thickness 0.15)
				)
				(justify left bottom)
				(hide yes)
			)
		)
		(property "Description" ""
			(at 262.89 167.64 0)
			(effects
				(font
					(size 1.27 1.27)
				)
				(hide yes)
			)
		)
		(property "Manufacturer" "Bourns"
			(at 283.21 190.5 0)
			(effects
				(font
					(size 1.27 1.27)
					(thickness 0.15)
				)
				(justify left bottom)
				(hide yes)
			)
		)
		(property "MPN" "CR0402-FX-1001GLF"
			(at 283.21 187.96 0)
			(effects
				(font
					(size 1.27 1.27)
					(thickness 0.15)
				)
				(justify left bottom)
				(hide yes)
			)
		)
		(property "Val" "1k"
			(at 260.35 167.005 0)
			(effects
				(font
					(size 1.27 1.27)
					(thickness 0.15)
				)
				(justify left bottom)
			)
		)
		(property "License" "Apache-2.0"
			(at 283.21 193.04 0)
			(effects
				(font
					(size 1.27 1.27)
					(thickness 0.15)
				)
				(justify left bottom)
				(hide yes)
			)
		)
		(property "Author" "Antmicro"
			(at 283.21 195.58 0)
			(effects
				(font
					(size 1.27 1.27)
					(thickness 0.15)
				)
				(justify left bottom)
				(hide yes)
			)
		)
		(property "Tolerance" "1%"
			(at 283.21 177.8 0)
			(effects
				(font
					(size 1.27 1.27)
				)
				(justify left bottom)
				(hide yes)
			)
		)
		(pin "1"
		)
		(pin "2"
		)
		(instances
			(project "jetson-orin-baseboard"
				(path ""
					(reference "R96")
					(unit 1)
				)
			)
		)
	)
	(symbol
		(lib_name "+3V3_1")
		(lib_id "antmicropower:+3V3")
		(at 16.51 31.75 0)
		(unit 1)
		(exclude_from_sim no)
		(in_bom yes)
		(on_board yes)
		(dnp no)
		(property "Reference" "#PWR046"
			(at 16.51 35.56 0)
			(effects
				(font
					(size 1.27 1.27)
				)
				(justify left bottom)
				(hide yes)
			)
		)
		(property "Value" "+3V3"
			(at 13.335 27.94 0)
			(effects
				(font
					(size 1.27 1.27)
					(thickness 0.15)
				)
				(justify left)
			)
		)
		(property "Footprint" ""
			(at 31.75 39.37 0)
			(effects
				(font
					(size 1.27 1.27)
					(thickness 0.15)
				)
				(justify left bottom)
				(hide yes)
			)
		)
		(property "Datasheet" ""
			(at 31.75 41.91 0)
			(effects
				(font
					(size 1.27 1.27)
					(thickness 0.15)
				)
				(justify left bottom)
				(hide yes)
			)
		)
		(property "Description" ""
			(at 16.51 31.75 0)
			(effects
				(font
					(size 1.27 1.27)
				)
				(hide yes)
			)
		)
		(property "Author" "Antmicro"
			(at 31.75 34.29 0)
			(effects
				(font
					(size 1.27 1.27)
					(thickness 0.15)
				)
				(justify left bottom)
				(hide yes)
			)
		)
		(property "License" "Apache-2.0"
			(at 31.75 36.83 0)
			(effects
				(font
					(size 1.27 1.27)
					(thickness 0.15)
				)
				(justify left bottom)
				(hide yes)
			)
		)
		(pin "1"
		)
		(instances
			(project "jetson-orin-baseboard"
				(path ""
					(reference "#PWR046")
					(unit 1)
				)
			)
		)
	)
	(symbol
		(lib_name "GND_3")
		(lib_id "antmicropower:GND")
		(at 375.92 48.26 0)
		(mirror y)
		(unit 1)
		(exclude_from_sim no)
		(in_bom yes)
		(on_board yes)
		(dnp no)
		(property "Reference" "#PWR098"
			(at 375.92 54.61 0)
			(effects
				(font
					(size 1.27 1.27)
				)
				(justify left bottom)
				(hide yes)
			)
		)
		(property "Value" "GND"
			(at 375.92 52.07 0)
			(effects
				(font
					(size 1.27 1.27)
					(thickness 0.15)
				)
			)
		)
		(property "Footprint" ""
			(at 367.03 55.88 0)
			(effects
				(font
					(size 1.27 1.27)
					(thickness 0.15)
				)
				(justify left bottom)
				(hide yes)
			)
		)
		(property "Datasheet" ""
			(at 367.03 60.96 0)
			(effects
				(font
					(size 1.27 1.27)
					(thickness 0.15)
				)
				(justify left bottom)
				(hide yes)
			)
		)
		(property "Description" ""
			(at 375.92 48.26 0)
			(effects
				(font
					(size 1.27 1.27)
				)
				(hide yes)
			)
		)
		(property "Author" "Antmicro"
			(at 367.03 55.88 0)
			(effects
				(font
					(size 1.27 1.27)
					(thickness 0.15)
				)
				(justify left bottom)
				(hide yes)
			)
		)
		(property "License" "Apache-2.0"
			(at 367.03 58.42 0)
			(effects
				(font
					(size 1.27 1.27)
					(thickness 0.15)
				)
				(justify left bottom)
				(hide yes)
			)
		)
		(pin "1"
		)
		(instances
			(project "jetson-orin-baseboard"
				(path ""
					(reference "#PWR098")
					(unit 1)
				)
			)
		)
	)
	(symbol
		(lib_id "antmicroCapacitors0603:C_10u_25V_0603")
		(at 29.21 173.99 90)
		(mirror x)
		(unit 1)
		(exclude_from_sim no)
		(in_bom yes)
		(on_board yes)
		(dnp no)
		(fields_autoplaced yes)
		(property "Reference" "C32"
			(at 31.75 175.2663 90)
			(effects
				(font
					(size 1.27 1.27)
				)
				(justify right)
			)
		)
		(property "Value" "C_10u_25V_0603"
			(at 39.37 194.31 0)
			(effects
				(font
					(size 1.27 1.27)
					(thickness 0.15)
				)
				(justify left bottom)
				(hide yes)
			)
		)
		(property "Footprint" "antmicro-footprints:C_0603_1608Metric"
			(at 41.91 194.31 0)
			(effects
				(font
					(size 1.27 1.27)
					(thickness 0.15)
				)
				(justify left bottom)
				(hide yes)
			)
		)
		(property "Datasheet" "https://product.tdk.com/en/search/capacitor/ceramic/mlcc/info?part_no=C1608X5R1E106M080AC"
			(at 44.45 194.31 0)
			(effects
				(font
					(size 1.27 1.27)
					(thickness 0.15)
				)
				(justify left bottom)
				(hide yes)
			)
		)
		(property "Description" ""
			(at 29.21 173.99 0)
			(effects
				(font
					(size 1.27 1.27)
				)
				(hide yes)
			)
		)
		(property "Manufacturer" "TDK"
			(at 49.53 194.31 0)
			(effects
				(font
					(size 1.27 1.27)
					(thickness 0.15)
				)
				(justify left bottom)
				(hide yes)
			)
		)
		(property "MPN" "C1608X5R1E106M080AC"
			(at 46.99 194.31 0)
			(effects
				(font
					(size 1.27 1.27)
					(thickness 0.15)
				)
				(justify left bottom)
				(hide yes)
			)
		)
		(property "Val" "10u"
			(at 31.75 177.8063 90)
			(effects
				(font
					(size 1.27 1.27)
					(thickness 0.15)
				)
				(justify right)
			)
		)
		(property "License" "Apache-2.0"
			(at 52.07 194.31 0)
			(effects
				(font
					(size 1.27 1.27)
					(thickness 0.15)
				)
				(justify left bottom)
				(hide yes)
			)
		)
		(property "Author" "Antmicro"
			(at 54.61 194.31 0)
			(effects
				(font
					(size 1.27 1.27)
					(thickness 0.15)
				)
				(justify left bottom)
				(hide yes)
			)
		)
		(property "Voltage" "25V"
			(at 57.15 194.31 0)
			(effects
				(font
					(size 1.27 1.27)
				)
				(justify left bottom)
				(hide yes)
			)
		)
		(property "Dielectric" ""
			(at 59.69 194.31 0)
			(effects
				(font
					(size 1.27 1.27)
				)
				(justify left bottom)
				(hide yes)
			)
		)
		(pin "1"
		)
		(pin "2"
		)
		(instances
			(project "jetson-orin-baseboard"
				(path ""
					(reference "C32")
					(unit 1)
				)
			)
		)
	)
	(symbol
		(lib_id "antmicroLogicTranslatorsLevelShifters:NTS0102_XSON")
		(at 110.49 242.57 0)
		(unit 1)
		(exclude_from_sim no)
		(in_bom yes)
		(on_board yes)
		(dnp no)
		(fields_autoplaced yes)
		(property "Reference" "U47"
			(at 120.65 234.95 0)
			(effects
				(font
					(size 1.27 1.27)
					(thickness 0.15)
				)
			)
		)
		(property "Value" "NTS0102_XSON"
			(at 146.05 250.19 0)
			(effects
				(font
					(size 1.27 1.27)
					(thickness 0.15)
				)
				(justify left bottom)
				(hide yes)
			)
		)
		(property "Footprint" "antmicro-footprints:XSON-8_1x1.95mm_P0.5mm"
			(at 146.05 252.73 0)
			(effects
				(font
					(size 1.27 1.27)
					(thickness 0.15)
				)
				(justify left bottom)
				(hide yes)
			)
		)
		(property "Datasheet" "http://www.farnell.com/datasheets/1760723.pdf"
			(at 146.05 255.27 0)
			(effects
				(font
					(size 1.27 1.27)
					(thickness 0.15)
				)
				(justify left bottom)
				(hide yes)
			)
		)
		(property "Description" ""
			(at 110.49 242.57 0)
			(effects
				(font
					(size 1.27 1.27)
				)
				(hide yes)
			)
		)
		(property "MPN" "NTS0102GT"
			(at 120.65 237.49 0)
			(effects
				(font
					(size 1.27 1.27)
					(thickness 0.15)
				)
			)
		)
		(property "Manufacturer" "NXP"
			(at 146.05 257.81 0)
			(effects
				(font
					(size 1.27 1.27)
					(thickness 0.15)
				)
				(justify left bottom)
				(hide yes)
			)
		)
		(property "Author" "Antmicro"
			(at 146.05 260.35 0)
			(effects
				(font
					(size 1.27 1.27)
					(thickness 0.15)
				)
				(justify left bottom)
				(hide yes)
			)
		)
		(property "License" "Apache-2.0"
			(at 146.05 262.89 0)
			(effects
				(font
					(size 1.27 1.27)
					(thickness 0.15)
				)
				(justify left bottom)
				(hide yes)
			)
		)
		(pin "2"
		)
		(pin "8"
		)
		(pin "7"
		)
		(pin "4"
		)
		(pin "5"
		)
		(pin "3"
		)
		(pin "6"
		)
		(pin "1"
		)
		(instances
			(project "jetson-orin-baseboard"
				(path ""
					(reference "U47")
					(unit 1)
				)
			)
		)
	)
	(symbol
		(lib_id "antmicroCapacitors0402:C_4u7_25V_0402")
		(at 273.05 64.77 270)
		(unit 1)
		(exclude_from_sim no)
		(in_bom yes)
		(on_board yes)
		(dnp no)
		(fields_autoplaced yes)
		(property "Reference" "C148"
			(at 275.59 66.0463 90)
			(effects
				(font
					(size 1.27 1.27)
				)
				(justify left)
			)
		)
		(property "Value" "C_4u7_25V_0402"
			(at 262.89 85.09 0)
			(effects
				(font
					(size 1.27 1.27)
					(thickness 0.15)
				)
				(justify left bottom)
				(hide yes)
			)
		)
		(property "Footprint" "antmicro-footprints:C_0402_1005Metric"
			(at 260.35 85.09 0)
			(effects
				(font
					(size 1.27 1.27)
					(thickness 0.15)
				)
				(justify left bottom)
				(hide yes)
			)
		)
		(property "Datasheet" "https://www.murata.com/products/productdetail?partno=GRM155C61E475ME15%23"
			(at 257.81 85.09 0)
			(effects
				(font
					(size 1.27 1.27)
					(thickness 0.15)
				)
				(justify left bottom)
				(hide yes)
			)
		)
		(property "Description" ""
			(at 273.05 64.77 0)
			(effects
				(font
					(size 1.27 1.27)
				)
				(hide yes)
			)
		)
		(property "Manufacturer" "Murata"
			(at 252.73 85.09 0)
			(effects
				(font
					(size 1.27 1.27)
					(thickness 0.15)
				)
				(justify left bottom)
				(hide yes)
			)
		)
		(property "MPN" "GRM155C61E475ME15J"
			(at 255.27 85.09 0)
			(effects
				(font
					(size 1.27 1.27)
					(thickness 0.15)
				)
				(justify left bottom)
				(hide yes)
			)
		)
		(property "Val" "4u7"
			(at 275.59 68.5863 90)
			(effects
				(font
					(size 1.27 1.27)
					(thickness 0.15)
				)
				(justify left)
			)
		)
		(property "License" "Apache-2.0"
			(at 250.19 85.09 0)
			(effects
				(font
					(size 1.27 1.27)
					(thickness 0.15)
				)
				(justify left bottom)
				(hide yes)
			)
		)
		(property "Author" "Antmicro"
			(at 247.65 85.09 0)
			(effects
				(font
					(size 1.27 1.27)
					(thickness 0.15)
				)
				(justify left bottom)
				(hide yes)
			)
		)
		(property "Voltage" "25V"
			(at 245.11 85.09 0)
			(effects
				(font
					(size 1.27 1.27)
				)
				(justify left bottom)
				(hide yes)
			)
		)
		(property "Dielectric" "X5S"
			(at 242.57 85.09 0)
			(effects
				(font
					(size 1.27 1.27)
				)
				(justify left bottom)
				(hide yes)
			)
		)
		(pin "1"
		)
		(pin "2"
		)
		(instances
			(project "jetson-orin-baseboard"
				(path ""
					(reference "C148")
					(unit 1)
				)
			)
		)
	)
	(symbol
		(lib_id "antmicroCapacitors0402:C_100n_0402")
		(at 271.78 106.68 0)
		(unit 1)
		(exclude_from_sim no)
		(in_bom yes)
		(on_board yes)
		(dnp no)
		(property "Reference" "C60"
			(at 275.59 106.045 0)
			(effects
				(font
					(size 1.27 1.27)
				)
				(justify left bottom)
			)
		)
		(property "Value" "C_100n_0402"
			(at 292.1 116.84 0)
			(effects
				(font
					(size 1.27 1.27)
					(thickness 0.15)
				)
				(justify left bottom)
				(hide yes)
			)
		)
		(property "Footprint" "antmicro-footprints:C_0402_1005Metric"
			(at 292.1 119.38 0)
			(effects
				(font
					(size 1.27 1.27)
					(thickness 0.15)
				)
				(justify left bottom)
				(hide yes)
			)
		)
		(property "Datasheet" "https://www.murata.com/products/productdetail?partno=GRM155R61H104KE14%23"
			(at 292.1 121.92 0)
			(effects
				(font
					(size 1.27 1.27)
					(thickness 0.15)
				)
				(justify left bottom)
				(hide yes)
			)
		)
		(property "Description" ""
			(at 271.78 106.68 0)
			(effects
				(font
					(size 1.27 1.27)
				)
				(hide yes)
			)
		)
		(property "Manufacturer" "Murata"
			(at 292.1 127 0)
			(effects
				(font
					(size 1.27 1.27)
					(thickness 0.15)
				)
				(justify left bottom)
				(hide yes)
			)
		)
		(property "MPN" "GRM155R61H104KE14D"
			(at 292.1 124.46 0)
			(effects
				(font
					(size 1.27 1.27)
					(thickness 0.15)
				)
				(justify left bottom)
				(hide yes)
			)
		)
		(property "Val" "100n"
			(at 267.97 108.585 0)
			(effects
				(font
					(size 1.27 1.27)
					(thickness 0.15)
				)
				(justify left bottom)
			)
		)
		(property "License" "Apache-2.0"
			(at 292.1 129.54 0)
			(effects
				(font
					(size 1.27 1.27)
					(thickness 0.15)
				)
				(justify left bottom)
				(hide yes)
			)
		)
		(property "Author" "Antmicro"
			(at 292.1 132.08 0)
			(effects
				(font
					(size 1.27 1.27)
					(thickness 0.15)
				)
				(justify left bottom)
				(hide yes)
			)
		)
		(property "Voltage" "50V"
			(at 292.1 134.62 0)
			(effects
				(font
					(size 1.27 1.27)
				)
				(justify left bottom)
				(hide yes)
			)
		)
		(property "Dielectric" "X5R"
			(at 292.1 137.16 0)
			(effects
				(font
					(size 1.27 1.27)
				)
				(justify left bottom)
				(hide yes)
			)
		)
		(pin "1"
		)
		(pin "2"
		)
		(instances
			(project "jetson-orin-baseboard"
				(path ""
					(reference "C60")
					(unit 1)
				)
			)
		)
	)
	(symbol
		(lib_id "antmicroResistors0402:R_100k_0402")
		(at 170.18 142.24 90)
		(unit 1)
		(exclude_from_sim no)
		(in_bom yes)
		(on_board yes)
		(dnp no)
		(fields_autoplaced yes)
		(property "Reference" "R207"
			(at 172.72 138.43 90)
			(effects
				(font
					(size 1.27 1.27)
				)
				(justify right)
			)
		)
		(property "Value" "R_100k_0402"
			(at 182.88 121.92 0)
			(effects
				(font
					(size 1.27 1.27)
					(thickness 0.15)
				)
				(justify left bottom)
				(hide yes)
			)
		)
		(property "Footprint" "antmicro-footprints:R_0402_1005Metric"
			(at 185.42 121.92 0)
			(effects
				(font
					(size 1.27 1.27)
					(thickness 0.15)
				)
				(justify left bottom)
				(hide yes)
			)
		)
		(property "Datasheet" "https://www.bourns.com/docs/product-datasheets/cr.pdf"
			(at 187.96 121.92 0)
			(effects
				(font
					(size 1.27 1.27)
					(thickness 0.15)
				)
				(justify left bottom)
				(hide yes)
			)
		)
		(property "Description" ""
			(at 170.18 142.24 0)
			(effects
				(font
					(size 1.27 1.27)
				)
				(hide yes)
			)
		)
		(property "Manufacturer" "Bourns"
			(at 193.04 121.92 0)
			(effects
				(font
					(size 1.27 1.27)
					(thickness 0.15)
				)
				(justify left bottom)
				(hide yes)
			)
		)
		(property "MPN" "CR0402-FX-1003GLF"
			(at 190.5 121.92 0)
			(effects
				(font
					(size 1.27 1.27)
					(thickness 0.15)
				)
				(justify left bottom)
				(hide yes)
			)
		)
		(property "Val" "100k"
			(at 172.72 140.97 90)
			(effects
				(font
					(size 1.27 1.27)
					(thickness 0.15)
				)
				(justify right)
			)
		)
		(property "License" "Apache-2.0"
			(at 195.58 121.92 0)
			(effects
				(font
					(size 1.27 1.27)
					(thickness 0.15)
				)
				(justify left bottom)
				(hide yes)
			)
		)
		(property "Author" "Antmicro"
			(at 198.12 121.92 0)
			(effects
				(font
					(size 1.27 1.27)
					(thickness 0.15)
				)
				(justify left bottom)
				(hide yes)
			)
		)
		(property "Tolerance" "1%"
			(at 180.34 121.92 0)
			(effects
				(font
					(size 1.27 1.27)
				)
				(justify left bottom)
				(hide yes)
			)
		)
		(pin "1"
		)
		(pin "2"
		)
		(instances
			(project "jetson-orin-baseboard"
				(path ""
					(reference "R207")
					(unit 1)
				)
			)
		)
	)
	(symbol
		(lib_id "antmicroResistors0402:R_1k_0402")
		(at 262.89 157.48 0)
		(unit 1)
		(exclude_from_sim no)
		(in_bom no)
		(on_board yes)
		(dnp yes)
		(property "Reference" "R92"
			(at 268.605 156.845 0)
			(effects
				(font
					(size 1.27 1.27)
				)
				(justify left bottom)
			)
		)
		(property "Value" "R_1k_0402"
			(at 283.21 170.18 0)
			(effects
				(font
					(size 1.27 1.27)
					(thickness 0.15)
				)
				(justify left bottom)
				(hide yes)
			)
		)
		(property "Footprint" "antmicro-footprints:R_0402_1005Metric"
			(at 283.21 172.72 0)
			(effects
				(font
					(size 1.27 1.27)
					(thickness 0.15)
				)
				(justify left bottom)
				(hide yes)
			)
		)
		(property "Datasheet" "https://www.bourns.com/docs/product-datasheets/cr.pdf"
			(at 283.21 175.26 0)
			(effects
				(font
					(size 1.27 1.27)
					(thickness 0.15)
				)
				(justify left bottom)
				(hide yes)
			)
		)
		(property "Description" ""
			(at 262.89 157.48 0)
			(effects
				(font
					(size 1.27 1.27)
				)
				(hide yes)
			)
		)
		(property "Manufacturer" "Bourns"
			(at 283.21 180.34 0)
			(effects
				(font
					(size 1.27 1.27)
					(thickness 0.15)
				)
				(justify left bottom)
				(hide yes)
			)
		)
		(property "MPN" "CR0402-FX-1001GLF"
			(at 283.21 177.8 0)
			(effects
				(font
					(size 1.27 1.27)
					(thickness 0.15)
				)
				(justify left bottom)
				(hide yes)
			)
		)
		(property "Val" "1k"
			(at 260.35 156.845 0)
			(effects
				(font
					(size 1.27 1.27)
					(thickness 0.15)
				)
				(justify left bottom)
			)
		)
		(property "License" "Apache-2.0"
			(at 283.21 182.88 0)
			(effects
				(font
					(size 1.27 1.27)
					(thickness 0.15)
				)
				(justify left bottom)
				(hide yes)
			)
		)
		(property "Author" "Antmicro"
			(at 283.21 185.42 0)
			(effects
				(font
					(size 1.27 1.27)
					(thickness 0.15)
				)
				(justify left bottom)
				(hide yes)
			)
		)
		(property "Tolerance" "1%"
			(at 283.21 167.64 0)
			(effects
				(font
					(size 1.27 1.27)
				)
				(justify left bottom)
				(hide yes)
			)
		)
		(pin "1"
		)
		(pin "2"
		)
		(instances
			(project "jetson-orin-baseboard"
				(path ""
					(reference "R92")
					(unit 1)
				)
			)
		)
	)
	(symbol
		(lib_id "antmicroCapacitors0402:C_10u_0402")
		(at 273.05 85.09 90)
		(mirror x)
		(unit 1)
		(exclude_from_sim no)
		(in_bom yes)
		(on_board yes)
		(dnp no)
		(fields_autoplaced yes)
		(property "Reference" "C59"
			(at 275.59 86.3663 90)
			(effects
				(font
					(size 1.27 1.27)
					(thickness 0.15)
				)
				(justify right)
			)
		)
		(property "Value" "C_10u_0402"
			(at 283.21 105.41 0)
			(effects
				(font
					(size 1.27 1.27)
					(thickness 0.15)
				)
				(justify left bottom)
				(hide yes)
			)
		)
		(property "Footprint" "antmicro-footprints:C_0402_1005Metric"
			(at 285.75 105.41 0)
			(effects
				(font
					(size 1.27 1.27)
					(thickness 0.15)
				)
				(justify left bottom)
				(hide yes)
			)
		)
		(property "Datasheet" "https://www.yageo.com/en/Chart/Download/pdf/CC0402MRX5R5BB106"
			(at 288.29 105.41 0)
			(effects
				(font
					(size 1.27 1.27)
					(thickness 0.15)
				)
				(justify left bottom)
				(hide yes)
			)
		)
		(property "Description" ""
			(at 273.05 85.09 0)
			(effects
				(font
					(size 1.27 1.27)
				)
				(hide yes)
			)
		)
		(property "MPN" "CC0402MRX5R5BB106"
			(at 290.83 105.41 0)
			(effects
				(font
					(size 1.27 1.27)
					(thickness 0.15)
				)
				(justify left bottom)
				(hide yes)
			)
		)
		(property "Manufacturer" "YAGEO"
			(at 293.37 105.41 0)
			(effects
				(font
					(size 1.27 1.27)
					(thickness 0.15)
				)
				(justify left bottom)
				(hide yes)
			)
		)
		(property "License" "Apache-2.0"
			(at 295.91 105.41 0)
			(effects
				(font
					(size 1.27 1.27)
					(thickness 0.15)
				)
				(justify left bottom)
				(hide yes)
			)
		)
		(property "Author" "Antmicro"
			(at 298.45 105.41 0)
			(effects
				(font
					(size 1.27 1.27)
					(thickness 0.15)
				)
				(justify left bottom)
				(hide yes)
			)
		)
		(property "Val" "10u"
			(at 275.59 88.9063 90)
			(effects
				(font
					(size 1.27 1.27)
					(thickness 0.15)
				)
				(justify right)
			)
		)
		(property "Voltage" ""
			(at 300.99 105.41 0)
			(effects
				(font
					(size 1.27 1.27)
				)
				(justify left bottom)
				(hide yes)
			)
		)
		(property "Dielectric" ""
			(at 303.53 105.41 0)
			(effects
				(font
					(size 1.27 1.27)
				)
				(justify left bottom)
				(hide yes)
			)
		)
		(pin "1"
		)
		(pin "2"
		)
		(instances
			(project "jetson-orin-baseboard"
				(path ""
					(reference "C59")
					(unit 1)
				)
			)
		)
	)
	(symbol
		(lib_id "antmicropower:+3V3")
		(at 252.73 33.02 0)
		(unit 1)
		(exclude_from_sim no)
		(in_bom yes)
		(on_board yes)
		(dnp no)
		(property "Reference" "#PWR0355"
			(at 252.73 36.83 0)
			(effects
				(font
					(size 1.27 1.27)
				)
				(justify left bottom)
				(hide yes)
			)
		)
		(property "Value" "+3V3"
			(at 249.555 29.845 0)
			(effects
				(font
					(size 1.27 1.27)
					(thickness 0.15)
				)
				(justify left bottom)
			)
		)
		(property "Footprint" ""
			(at 267.97 40.64 0)
			(effects
				(font
					(size 1.27 1.27)
					(thickness 0.15)
				)
				(justify left bottom)
				(hide yes)
			)
		)
		(property "Datasheet" ""
			(at 267.97 43.18 0)
			(effects
				(font
					(size 1.27 1.27)
					(thickness 0.15)
				)
				(justify left bottom)
				(hide yes)
			)
		)
		(property "Description" ""
			(at 252.73 33.02 0)
			(effects
				(font
					(size 1.27 1.27)
				)
				(hide yes)
			)
		)
		(property "Author" "Antmicro"
			(at 267.97 35.56 0)
			(effects
				(font
					(size 1.27 1.27)
					(thickness 0.15)
				)
				(justify left bottom)
				(hide yes)
			)
		)
		(property "License" "Apache-2.0"
			(at 267.97 38.1 0)
			(effects
				(font
					(size 1.27 1.27)
					(thickness 0.15)
				)
				(justify left bottom)
				(hide yes)
			)
		)
		(pin "1"
		)
		(instances
			(project "jetson-orin-baseboard"
				(path ""
					(reference "#PWR0355")
					(unit 1)
				)
			)
		)
	)
	(symbol
		(lib_name "GND_3")
		(lib_id "antmicropower:GND")
		(at 41.91 227.33 0)
		(mirror y)
		(unit 1)
		(exclude_from_sim no)
		(in_bom yes)
		(on_board yes)
		(dnp no)
		(property "Reference" "#PWR035"
			(at 41.91 233.68 0)
			(effects
				(font
					(size 1.27 1.27)
				)
				(justify left bottom)
				(hide yes)
			)
		)
		(property "Value" "GND"
			(at 41.91 231.14 0)
			(effects
				(font
					(size 1.27 1.27)
					(thickness 0.15)
				)
			)
		)
		(property "Footprint" ""
			(at 33.02 234.95 0)
			(effects
				(font
					(size 1.27 1.27)
					(thickness 0.15)
				)
				(justify left bottom)
				(hide yes)
			)
		)
		(property "Datasheet" ""
			(at 33.02 240.03 0)
			(effects
				(font
					(size 1.27 1.27)
					(thickness 0.15)
				)
				(justify left bottom)
				(hide yes)
			)
		)
		(property "Description" ""
			(at 41.91 227.33 0)
			(effects
				(font
					(size 1.27 1.27)
				)
				(hide yes)
			)
		)
		(property "Author" "Antmicro"
			(at 33.02 234.95 0)
			(effects
				(font
					(size 1.27 1.27)
					(thickness 0.15)
				)
				(justify left bottom)
				(hide yes)
			)
		)
		(property "License" "Apache-2.0"
			(at 33.02 237.49 0)
			(effects
				(font
					(size 1.27 1.27)
					(thickness 0.15)
				)
				(justify left bottom)
				(hide yes)
			)
		)
		(pin "1"
		)
		(instances
			(project "jetson-orin-baseboard"
				(path ""
					(reference "#PWR035")
					(unit 1)
				)
			)
		)
	)
	(symbol
		(lib_name "GND_3")
		(lib_id "antmicropower:GND")
		(at 396.24 54.61 0)
		(mirror y)
		(unit 1)
		(exclude_from_sim no)
		(in_bom yes)
		(on_board yes)
		(dnp no)
		(property "Reference" "#PWR0271"
			(at 396.24 60.96 0)
			(effects
				(font
					(size 1.27 1.27)
				)
				(justify left bottom)
				(hide yes)
			)
		)
		(property "Value" "GND"
			(at 396.24 58.42 0)
			(effects
				(font
					(size 1.27 1.27)
					(thickness 0.15)
				)
			)
		)
		(property "Footprint" ""
			(at 387.35 62.23 0)
			(effects
				(font
					(size 1.27 1.27)
					(thickness 0.15)
				)
				(justify left bottom)
				(hide yes)
			)
		)
		(property "Datasheet" ""
			(at 387.35 67.31 0)
			(effects
				(font
					(size 1.27 1.27)
					(thickness 0.15)
				)
				(justify left bottom)
				(hide yes)
			)
		)
		(property "Description" ""
			(at 396.24 54.61 0)
			(effects
				(font
					(size 1.27 1.27)
				)
				(hide yes)
			)
		)
		(property "Author" "Antmicro"
			(at 387.35 62.23 0)
			(effects
				(font
					(size 1.27 1.27)
					(thickness 0.15)
				)
				(justify left bottom)
				(hide yes)
			)
		)
		(property "License" "Apache-2.0"
			(at 387.35 64.77 0)
			(effects
				(font
					(size 1.27 1.27)
					(thickness 0.15)
				)
				(justify left bottom)
				(hide yes)
			)
		)
		(pin "1"
		)
		(instances
			(project "jetson-orin-baseboard"
				(path ""
					(reference "#PWR0271")
					(unit 1)
				)
			)
		)
	)
	(symbol
		(lib_id "antmicroResistors0402:R_4k7_0402")
		(at 396.24 46.99 90)
		(unit 1)
		(exclude_from_sim no)
		(in_bom yes)
		(on_board yes)
		(dnp no)
		(property "Reference" "R106"
			(at 397.51 43.18 90)
			(effects
				(font
					(size 1.27 1.27)
				)
				(justify right)
			)
		)
		(property "Value" "R_4k7_0402"
			(at 408.94 26.67 0)
			(effects
				(font
					(size 1.27 1.27)
					(thickness 0.15)
				)
				(justify left bottom)
				(hide yes)
			)
		)
		(property "Footprint" "antmicro-footprints:R_0402_1005Metric"
			(at 411.48 26.67 0)
			(effects
				(font
					(size 1.27 1.27)
					(thickness 0.15)
				)
				(justify left bottom)
				(hide yes)
			)
		)
		(property "Datasheet" "https://www.bourns.com/docs/product-datasheets/cr.pdf"
			(at 414.02 26.67 0)
			(effects
				(font
					(size 1.27 1.27)
					(thickness 0.15)
				)
				(justify left bottom)
				(hide yes)
			)
		)
		(property "Description" ""
			(at 396.24 46.99 0)
			(effects
				(font
					(size 1.27 1.27)
				)
				(hide yes)
			)
		)
		(property "Manufacturer" "Bourns"
			(at 419.1 26.67 0)
			(effects
				(font
					(size 1.27 1.27)
					(thickness 0.15)
				)
				(justify left bottom)
				(hide yes)
			)
		)
		(property "MPN" "CR0402-FX-4701GLF"
			(at 416.56 26.67 0)
			(effects
				(font
					(size 1.27 1.27)
					(thickness 0.15)
				)
				(justify left bottom)
				(hide yes)
			)
		)
		(property "Val" "4k7"
			(at 397.51 45.72 90)
			(effects
				(font
					(size 1.27 1.27)
					(thickness 0.15)
				)
				(justify right)
			)
		)
		(property "License" "Apache-2.0"
			(at 421.64 26.67 0)
			(effects
				(font
					(size 1.27 1.27)
					(thickness 0.15)
				)
				(justify left bottom)
				(hide yes)
			)
		)
		(property "Author" "Antmicro"
			(at 424.18 26.67 0)
			(effects
				(font
					(size 1.27 1.27)
					(thickness 0.15)
				)
				(justify left bottom)
				(hide yes)
			)
		)
		(property "Tolerance" "1%"
			(at 406.4 26.67 0)
			(effects
				(font
					(size 1.27 1.27)
				)
				(justify left bottom)
				(hide yes)
			)
		)
		(pin "1"
		)
		(pin "2"
		)
		(instances
			(project "jetson-orin-baseboard"
				(path ""
					(reference "R106")
					(unit 1)
				)
			)
		)
	)
	(symbol
		(lib_id "antmicroUSBConnectors:USB-C_GCT_USB4105-GF-A")
		(at 373.38 207.01 0)
		(mirror y)
		(unit 1)
		(exclude_from_sim no)
		(in_bom yes)
		(on_board yes)
		(dnp no)
		(fields_autoplaced yes)
		(property "Reference" "J3"
			(at 376.555 200.025 0)
			(effects
				(font
					(size 1.27 1.27)
				)
				(justify right)
			)
		)
		(property "Value" "USB-C_GCT_USB4105-GF-A"
			(at 376.555 202.565 0)
			(effects
				(font
					(size 1.27 1.27)
					(thickness 0.15)
				)
				(justify right)
			)
		)
		(property "Footprint" "antmicro-footprints:USB-C_Receptacle_GCT_USB4105-GF-A"
			(at 335.28 214.63 0)
			(effects
				(font
					(size 1.27 1.27)
					(thickness 0.15)
				)
				(justify left bottom)
				(hide yes)
			)
		)
		(property "Datasheet" "https://gct.co/files/drawings/usb4105.pdf"
			(at 335.28 217.17 0)
			(effects
				(font
					(size 1.27 1.27)
					(thickness 0.15)
				)
				(justify left bottom)
				(hide yes)
			)
		)
		(property "Description" ""
			(at 373.38 207.01 0)
			(effects
				(font
					(size 1.27 1.27)
				)
				(hide yes)
			)
		)
		(property "Manufacturer" "GCT"
			(at 335.28 219.71 0)
			(effects
				(font
					(size 1.27 1.27)
					(thickness 0.15)
				)
				(justify left bottom)
				(hide yes)
			)
		)
		(property "MPN" "USB4105-GF-A"
			(at 335.28 222.25 0)
			(effects
				(font
					(size 1.27 1.27)
					(thickness 0.15)
				)
				(justify left bottom)
				(hide yes)
			)
		)
		(property "Author" "Antmicro"
			(at 335.28 224.79 0)
			(effects
				(font
					(size 1.27 1.27)
					(thickness 0.15)
				)
				(justify left bottom)
				(hide yes)
			)
		)
		(property "License" "Apache-2.0"
			(at 335.28 227.33 0)
			(effects
				(font
					(size 1.27 1.27)
					(thickness 0.15)
				)
				(justify left bottom)
				(hide yes)
			)
		)
		(pin "A1"
		)
		(pin "A12"
		)
		(pin "A4"
		)
		(pin "A5"
		)
		(pin "A6"
		)
		(pin "A7"
		)
		(pin "A8"
		)
		(pin "A9"
		)
		(pin "B1"
		)
		(pin "B12"
		)
		(pin "B4"
		)
		(pin "B5"
		)
		(pin "B6"
		)
		(pin "B7"
		)
		(pin "B8"
		)
		(pin "B9"
		)
		(pin "SH"
		)
		(instances
			(project "jetson-orin-baseboard"
				(path ""
					(reference "J3")
					(unit 1)
				)
			)
		)
	)
	(symbol
		(lib_name "GND_3")
		(lib_id "antmicropower:GND")
		(at 157.48 73.66 0)
		(mirror y)
		(unit 1)
		(exclude_from_sim no)
		(in_bom yes)
		(on_board yes)
		(dnp no)
		(property "Reference" "#PWR070"
			(at 157.48 80.01 0)
			(effects
				(font
					(size 1.27 1.27)
				)
				(justify left bottom)
				(hide yes)
			)
		)
		(property "Value" "GND"
			(at 157.48 77.47 0)
			(effects
				(font
					(size 1.27 1.27)
					(thickness 0.15)
				)
			)
		)
		(property "Footprint" ""
			(at 148.59 81.28 0)
			(effects
				(font
					(size 1.27 1.27)
					(thickness 0.15)
				)
				(justify left bottom)
				(hide yes)
			)
		)
		(property "Datasheet" ""
			(at 148.59 86.36 0)
			(effects
				(font
					(size 1.27 1.27)
					(thickness 0.15)
				)
				(justify left bottom)
				(hide yes)
			)
		)
		(property "Description" ""
			(at 157.48 73.66 0)
			(effects
				(font
					(size 1.27 1.27)
				)
				(hide yes)
			)
		)
		(property "Author" "Antmicro"
			(at 148.59 81.28 0)
			(effects
				(font
					(size 1.27 1.27)
					(thickness 0.15)
				)
				(justify left bottom)
				(hide yes)
			)
		)
		(property "License" "Apache-2.0"
			(at 148.59 83.82 0)
			(effects
				(font
					(size 1.27 1.27)
					(thickness 0.15)
				)
				(justify left bottom)
				(hide yes)
			)
		)
		(pin "1"
		)
		(instances
			(project "jetson-orin-baseboard"
				(path ""
					(reference "#PWR070")
					(unit 1)
				)
			)
		)
	)
	(symbol
		(lib_name "GND_3")
		(lib_id "antmicropower:GND")
		(at 360.68 140.97 0)
		(mirror y)
		(unit 1)
		(exclude_from_sim no)
		(in_bom yes)
		(on_board yes)
		(dnp no)
		(property "Reference" "#PWR0103"
			(at 360.68 147.32 0)
			(effects
				(font
					(size 1.27 1.27)
				)
				(justify left bottom)
				(hide yes)
			)
		)
		(property "Value" "GND"
			(at 360.68 144.78 0)
			(effects
				(font
					(size 1.27 1.27)
					(thickness 0.15)
				)
			)
		)
		(property "Footprint" ""
			(at 351.79 148.59 0)
			(effects
				(font
					(size 1.27 1.27)
					(thickness 0.15)
				)
				(justify left bottom)
				(hide yes)
			)
		)
		(property "Datasheet" ""
			(at 351.79 153.67 0)
			(effects
				(font
					(size 1.27 1.27)
					(thickness 0.15)
				)
				(justify left bottom)
				(hide yes)
			)
		)
		(property "Description" ""
			(at 360.68 140.97 0)
			(effects
				(font
					(size 1.27 1.27)
				)
				(hide yes)
			)
		)
		(property "Author" "Antmicro"
			(at 351.79 148.59 0)
			(effects
				(font
					(size 1.27 1.27)
					(thickness 0.15)
				)
				(justify left bottom)
				(hide yes)
			)
		)
		(property "License" "Apache-2.0"
			(at 351.79 151.13 0)
			(effects
				(font
					(size 1.27 1.27)
					(thickness 0.15)
				)
				(justify left bottom)
				(hide yes)
			)
		)
		(pin "1"
		)
		(instances
			(project "jetson-orin-baseboard"
				(path ""
					(reference "#PWR0103")
					(unit 1)
				)
			)
		)
	)
	(symbol
		(lib_name "GND_3")
		(lib_id "antmicropower:GND")
		(at 111.76 278.13 0)
		(mirror y)
		(unit 1)
		(exclude_from_sim no)
		(in_bom yes)
		(on_board yes)
		(dnp no)
		(property "Reference" "#PWR0358"
			(at 111.76 284.48 0)
			(effects
				(font
					(size 1.27 1.27)
				)
				(justify left bottom)
				(hide yes)
			)
		)
		(property "Value" "GND"
			(at 111.76 281.94 0)
			(effects
				(font
					(size 1.27 1.27)
					(thickness 0.15)
				)
			)
		)
		(property "Footprint" ""
			(at 102.87 285.75 0)
			(effects
				(font
					(size 1.27 1.27)
					(thickness 0.15)
				)
				(justify left bottom)
				(hide yes)
			)
		)
		(property "Datasheet" ""
			(at 102.87 290.83 0)
			(effects
				(font
					(size 1.27 1.27)
					(thickness 0.15)
				)
				(justify left bottom)
				(hide yes)
			)
		)
		(property "Description" ""
			(at 111.76 278.13 0)
			(effects
				(font
					(size 1.27 1.27)
				)
				(hide yes)
			)
		)
		(property "Author" "Antmicro"
			(at 102.87 285.75 0)
			(effects
				(font
					(size 1.27 1.27)
					(thickness 0.15)
				)
				(justify left bottom)
				(hide yes)
			)
		)
		(property "License" "Apache-2.0"
			(at 102.87 288.29 0)
			(effects
				(font
					(size 1.27 1.27)
					(thickness 0.15)
				)
				(justify left bottom)
				(hide yes)
			)
		)
		(pin "1"
		)
		(instances
			(project "jetson-orin-baseboard"
				(path ""
					(reference "#PWR0358")
					(unit 1)
				)
			)
		)
	)
	(symbol
		(lib_name "GND_3")
		(lib_id "antmicropower:GND")
		(at 40.64 179.07 0)
		(mirror y)
		(unit 1)
		(exclude_from_sim no)
		(in_bom yes)
		(on_board yes)
		(dnp no)
		(property "Reference" "#PWR063"
			(at 40.64 185.42 0)
			(effects
				(font
					(size 1.27 1.27)
				)
				(justify left bottom)
				(hide yes)
			)
		)
		(property "Value" "GND"
			(at 40.64 182.88 0)
			(effects
				(font
					(size 1.27 1.27)
					(thickness 0.15)
				)
			)
		)
		(property "Footprint" ""
			(at 31.75 186.69 0)
			(effects
				(font
					(size 1.27 1.27)
					(thickness 0.15)
				)
				(justify left bottom)
				(hide yes)
			)
		)
		(property "Datasheet" ""
			(at 31.75 191.77 0)
			(effects
				(font
					(size 1.27 1.27)
					(thickness 0.15)
				)
				(justify left bottom)
				(hide yes)
			)
		)
		(property "Description" ""
			(at 40.64 179.07 0)
			(effects
				(font
					(size 1.27 1.27)
				)
				(hide yes)
			)
		)
		(property "Author" "Antmicro"
			(at 31.75 186.69 0)
			(effects
				(font
					(size 1.27 1.27)
					(thickness 0.15)
				)
				(justify left bottom)
				(hide yes)
			)
		)
		(property "License" "Apache-2.0"
			(at 31.75 189.23 0)
			(effects
				(font
					(size 1.27 1.27)
					(thickness 0.15)
				)
				(justify left bottom)
				(hide yes)
			)
		)
		(pin "1"
		)
		(instances
			(project "jetson-orin-baseboard"
				(path ""
					(reference "#PWR063")
					(unit 1)
				)
			)
		)
	)
	(symbol
		(lib_id "antmicroMemory:W25Q80DV_USON")
		(at 50.8 134.62 0)
		(unit 1)
		(exclude_from_sim no)
		(in_bom yes)
		(on_board yes)
		(dnp no)
		(property "Reference" "U7"
			(at 60.325 128.27 0)
			(effects
				(font
					(size 1.27 1.27)
				)
			)
		)
		(property "Value" "W25Q80DV_USON"
			(at 88.9 143.51 0)
			(effects
				(font
					(size 1.27 1.27)
					(thickness 0.15)
				)
				(justify left bottom)
				(hide yes)
			)
		)
		(property "Footprint" "antmicro-footprints:USON-8_2x3mm_P0.5mm"
			(at 88.9 146.05 0)
			(effects
				(font
					(size 1.27 1.27)
					(thickness 0.15)
				)
				(justify left bottom)
				(hide yes)
			)
		)
		(property "Datasheet" "https://www.mouser.com/datasheet/2/949/w25q80dv_dl_revh_10022015-1489677.pdf"
			(at 88.9 148.59 0)
			(effects
				(font
					(size 1.27 1.27)
					(thickness 0.15)
				)
				(justify left bottom)
				(hide yes)
			)
		)
		(property "Description" ""
			(at 50.8 134.62 0)
			(effects
				(font
					(size 1.27 1.27)
				)
				(hide yes)
			)
		)
		(property "MPN" "W25Q80DVUXIE TR"
			(at 60.325 130.81 0)
			(effects
				(font
					(size 1.27 1.27)
					(thickness 0.15)
				)
			)
		)
		(property "Manufacturer" "Winbond"
			(at 88.9 153.67 0)
			(effects
				(font
					(size 1.27 1.27)
					(thickness 0.15)
				)
				(justify left bottom)
				(hide yes)
			)
		)
		(property "Author" "Antmicro"
			(at 88.9 156.21 0)
			(effects
				(font
					(size 1.27 1.27)
					(thickness 0.15)
				)
				(justify left bottom)
				(hide yes)
			)
		)
		(property "License" "Apache-2.0"
			(at 88.9 158.75 0)
			(effects
				(font
					(size 1.27 1.27)
					(thickness 0.15)
				)
				(justify left bottom)
				(hide yes)
			)
		)
		(pin "1"
		)
		(pin "2"
		)
		(pin "3"
		)
		(pin "4"
		)
		(pin "5"
		)
		(pin "6"
		)
		(pin "7"
		)
		(pin "8"
		)
		(pin "EP"
		)
		(instances
			(project "jetson-orin-baseboard"
				(path ""
					(reference "U7")
					(unit 1)
				)
			)
		)
	)
	(symbol
		(lib_name "R_10k_0402_3")
		(lib_id "antmicroResistors0402:R_10k_0402")
		(at 207.01 218.44 90)
		(unit 1)
		(exclude_from_sim no)
		(in_bom yes)
		(on_board yes)
		(dnp no)
		(property "Reference" "R77"
			(at 208.28 214.63 90)
			(effects
				(font
					(size 1.27 1.27)
				)
				(justify right)
			)
		)
		(property "Value" "R_10k_0402"
			(at 219.71 198.12 0)
			(effects
				(font
					(size 1.27 1.27)
					(thickness 0.15)
				)
				(justify left bottom)
				(hide yes)
			)
		)
		(property "Footprint" "antmicro-footprints:R_0402_1005Metric"
			(at 222.25 198.12 0)
			(effects
				(font
					(size 1.27 1.27)
					(thickness 0.15)
				)
				(justify left bottom)
				(hide yes)
			)
		)
		(property "Datasheet" "https://www.bourns.com/docs/product-datasheets/cr.pdf"
			(at 224.79 198.12 0)
			(effects
				(font
					(size 1.27 1.27)
					(thickness 0.15)
				)
				(justify left bottom)
				(hide yes)
			)
		)
		(property "Description" ""
			(at 207.01 218.44 0)
			(effects
				(font
					(size 1.27 1.27)
				)
				(hide yes)
			)
		)
		(property "Manufacturer" "Bourns"
			(at 229.87 198.12 0)
			(effects
				(font
					(size 1.27 1.27)
					(thickness 0.15)
				)
				(justify left bottom)
				(hide yes)
			)
		)
		(property "MPN" "CR0402-FX-1002GLF"
			(at 227.33 198.12 0)
			(effects
				(font
					(size 1.27 1.27)
					(thickness 0.15)
				)
				(justify left bottom)
				(hide yes)
			)
		)
		(property "Val" "10k"
			(at 208.28 217.17 90)
			(effects
				(font
					(size 1.27 1.27)
					(thickness 0.15)
				)
				(justify right)
			)
		)
		(property "License" "Apache-2.0"
			(at 232.41 198.12 0)
			(effects
				(font
					(size 1.27 1.27)
					(thickness 0.15)
				)
				(justify left bottom)
				(hide yes)
			)
		)
		(property "Author" "Antmicro"
			(at 234.95 198.12 0)
			(effects
				(font
					(size 1.27 1.27)
					(thickness 0.15)
				)
				(justify left bottom)
				(hide yes)
			)
		)
		(property "Tolerance" "1%"
			(at 217.17 198.12 0)
			(effects
				(font
					(size 1.27 1.27)
				)
				(justify left bottom)
				(hide yes)
			)
		)
		(pin "1"
		)
		(pin "2"
		)
		(instances
			(project "jetson-orin-baseboard"
				(path ""
					(reference "R77")
					(unit 1)
				)
			)
		)
	)
	(symbol
		(lib_id "antmicroCapacitors0402:C_100n_0402")
		(at 262.89 64.77 270)
		(unit 1)
		(exclude_from_sim no)
		(in_bom yes)
		(on_board yes)
		(dnp no)
		(fields_autoplaced yes)
		(property "Reference" "C58"
			(at 265.43 66.0463 90)
			(effects
				(font
					(size 1.27 1.27)
				)
				(justify left)
			)
		)
		(property "Value" "C_100n_0402"
			(at 252.73 85.09 0)
			(effects
				(font
					(size 1.27 1.27)
					(thickness 0.15)
				)
				(justify left bottom)
				(hide yes)
			)
		)
		(property "Footprint" "antmicro-footprints:C_0402_1005Metric"
			(at 250.19 85.09 0)
			(effects
				(font
					(size 1.27 1.27)
					(thickness 0.15)
				)
				(justify left bottom)
				(hide yes)
			)
		)
		(property "Datasheet" "https://www.murata.com/products/productdetail?partno=GRM155R61H104KE14%23"
			(at 247.65 85.09 0)
			(effects
				(font
					(size 1.27 1.27)
					(thickness 0.15)
				)
				(justify left bottom)
				(hide yes)
			)
		)
		(property "Description" ""
			(at 262.89 64.77 0)
			(effects
				(font
					(size 1.27 1.27)
				)
				(hide yes)
			)
		)
		(property "MPN" "GRM155R61H104KE14D"
			(at 245.11 85.09 0)
			(effects
				(font
					(size 1.27 1.27)
					(thickness 0.15)
				)
				(justify left bottom)
				(hide yes)
			)
		)
		(property "Manufacturer" "Murata"
			(at 242.57 85.09 0)
			(effects
				(font
					(size 1.27 1.27)
					(thickness 0.15)
				)
				(justify left bottom)
				(hide yes)
			)
		)
		(property "Val" "100n"
			(at 265.43 68.5863 90)
			(effects
				(font
					(size 1.27 1.27)
					(thickness 0.15)
				)
				(justify left)
			)
		)
		(property "License" "Apache-2.0"
			(at 240.03 85.09 0)
			(effects
				(font
					(size 1.27 1.27)
					(thickness 0.15)
				)
				(justify left bottom)
				(hide yes)
			)
		)
		(property "Author" "Antmicro"
			(at 237.49 85.09 0)
			(effects
				(font
					(size 1.27 1.27)
					(thickness 0.15)
				)
				(justify left bottom)
				(hide yes)
			)
		)
		(property "Voltage" "50V"
			(at 234.95 85.09 0)
			(effects
				(font
					(size 1.27 1.27)
				)
				(justify left bottom)
				(hide yes)
			)
		)
		(property "Dielectric" "X5R"
			(at 232.41 85.09 0)
			(effects
				(font
					(size 1.27 1.27)
				)
				(justify left bottom)
				(hide yes)
			)
		)
		(pin "1"
		)
		(pin "2"
		)
		(instances
			(project "jetson-orin-baseboard"
				(path ""
					(reference "C58")
					(unit 1)
				)
			)
		)
	)
	(symbol
		(lib_name "GND_3")
		(lib_id "antmicropower:GND")
		(at 262.89 41.91 0)
		(mirror y)
		(unit 1)
		(exclude_from_sim no)
		(in_bom yes)
		(on_board yes)
		(dnp no)
		(property "Reference" "#PWR083"
			(at 262.89 48.26 0)
			(effects
				(font
					(size 1.27 1.27)
				)
				(justify left bottom)
				(hide yes)
			)
		)
		(property "Value" "GND"
			(at 262.89 45.72 0)
			(effects
				(font
					(size 1.27 1.27)
					(thickness 0.15)
				)
			)
		)
		(property "Footprint" ""
			(at 254 49.53 0)
			(effects
				(font
					(size 1.27 1.27)
					(thickness 0.15)
				)
				(justify left bottom)
				(hide yes)
			)
		)
		(property "Datasheet" ""
			(at 254 54.61 0)
			(effects
				(font
					(size 1.27 1.27)
					(thickness 0.15)
				)
				(justify left bottom)
				(hide yes)
			)
		)
		(property "Description" ""
			(at 262.89 41.91 0)
			(effects
				(font
					(size 1.27 1.27)
				)
				(hide yes)
			)
		)
		(property "Author" "Antmicro"
			(at 254 49.53 0)
			(effects
				(font
					(size 1.27 1.27)
					(thickness 0.15)
				)
				(justify left bottom)
				(hide yes)
			)
		)
		(property "License" "Apache-2.0"
			(at 254 52.07 0)
			(effects
				(font
					(size 1.27 1.27)
					(thickness 0.15)
				)
				(justify left bottom)
				(hide yes)
			)
		)
		(pin "1"
		)
		(instances
			(project "jetson-orin-baseboard"
				(path ""
					(reference "#PWR083")
					(unit 1)
				)
			)
		)
	)
	(symbol
		(lib_id "antmicroResistors0402:R_0R_0402")
		(at 278.13 53.34 0)
		(unit 1)
		(exclude_from_sim no)
		(in_bom yes)
		(on_board yes)
		(dnp no)
		(property "Reference" "R84"
			(at 283.21 52.705 0)
			(effects
				(font
					(size 1.27 1.27)
				)
				(justify left bottom)
			)
		)
		(property "Value" "R_0R_0402"
			(at 298.45 66.04 0)
			(effects
				(font
					(size 1.27 1.27)
					(thickness 0.15)
				)
				(justify left bottom)
				(hide yes)
			)
		)
		(property "Footprint" "antmicro-footprints:R_0402_1005Metric"
			(at 298.45 68.58 0)
			(effects
				(font
					(size 1.27 1.27)
					(thickness 0.15)
				)
				(justify left bottom)
				(hide yes)
			)
		)
		(property "Datasheet" "https://industrial.panasonic.com/cdbs/www-data/pdf/RDA0000/AOA0000C301.pdf"
			(at 298.45 71.12 0)
			(effects
				(font
					(size 1.27 1.27)
					(thickness 0.15)
				)
				(justify left bottom)
				(hide yes)
			)
		)
		(property "Description" ""
			(at 278.13 53.34 0)
			(effects
				(font
					(size 1.27 1.27)
				)
				(hide yes)
			)
		)
		(property "Manufacturer" "Panasonic"
			(at 298.45 76.2 0)
			(effects
				(font
					(size 1.27 1.27)
					(thickness 0.15)
				)
				(justify left bottom)
				(hide yes)
			)
		)
		(property "MPN" "ERJ2GE0R00X"
			(at 298.45 73.66 0)
			(effects
				(font
					(size 1.27 1.27)
					(thickness 0.15)
				)
				(justify left bottom)
				(hide yes)
			)
		)
		(property "Val" "0R"
			(at 275.59 52.705 0)
			(effects
				(font
					(size 1.27 1.27)
					(thickness 0.15)
				)
				(justify left bottom)
			)
		)
		(property "License" "Apache-2.0"
			(at 298.45 78.74 0)
			(effects
				(font
					(size 1.27 1.27)
					(thickness 0.15)
				)
				(justify left bottom)
				(hide yes)
			)
		)
		(property "Author" "Antmicro"
			(at 298.45 81.28 0)
			(effects
				(font
					(size 1.27 1.27)
					(thickness 0.15)
				)
				(justify left bottom)
				(hide yes)
			)
		)
		(property "Tolerance" "~"
			(at 298.45 63.5 0)
			(effects
				(font
					(size 1.27 1.27)
				)
				(justify left bottom)
				(hide yes)
			)
		)
		(property "Current" "1A"
			(at 298.45 83.82 0)
			(effects
				(font
					(size 1.27 1.27)
					(thickness 0.15)
				)
				(justify left bottom)
				(hide yes)
			)
		)
		(pin "1"
		)
		(pin "2"
		)
		(instances
			(project "jetson-orin-baseboard"
				(path ""
					(reference "R84")
					(unit 1)
				)
			)
		)
	)
	(symbol
		(lib_name "R_0R_0402_5")
		(lib_id "antmicroResistors0402:R_0R_0402")
		(at 114.3 99.06 0)
		(mirror y)
		(unit 1)
		(exclude_from_sim no)
		(in_bom yes)
		(on_board yes)
		(dnp no)
		(property "Reference" "R71"
			(at 114.3 98.425 0)
			(effects
				(font
					(size 1.27 1.27)
				)
				(justify right bottom)
			)
		)
		(property "Value" "R_0R_0402"
			(at 93.98 111.76 0)
			(effects
				(font
					(size 1.27 1.27)
					(thickness 0.15)
				)
				(justify left bottom)
				(hide yes)
			)
		)
		(property "Footprint" "antmicro-footprints:R_0402_1005Metric"
			(at 93.98 114.3 0)
			(effects
				(font
					(size 1.27 1.27)
					(thickness 0.15)
				)
				(justify left bottom)
				(hide yes)
			)
		)
		(property "Datasheet" "https://industrial.panasonic.com/cdbs/www-data/pdf/RDA0000/AOA0000C301.pdf"
			(at 93.98 116.84 0)
			(effects
				(font
					(size 1.27 1.27)
					(thickness 0.15)
				)
				(justify left bottom)
				(hide yes)
			)
		)
		(property "Description" ""
			(at 114.3 99.06 0)
			(effects
				(font
					(size 1.27 1.27)
				)
				(hide yes)
			)
		)
		(property "Manufacturer" "Panasonic"
			(at 93.98 121.92 0)
			(effects
				(font
					(size 1.27 1.27)
					(thickness 0.15)
				)
				(justify left bottom)
				(hide yes)
			)
		)
		(property "MPN" "ERJ2GE0R00X"
			(at 93.98 119.38 0)
			(effects
				(font
					(size 1.27 1.27)
					(thickness 0.15)
				)
				(justify left bottom)
				(hide yes)
			)
		)
		(property "Val" "0R"
			(at 106.68 98.425 0)
			(effects
				(font
					(size 1.27 1.27)
					(thickness 0.15)
				)
				(justify right bottom)
			)
		)
		(property "License" "Apache-2.0"
			(at 93.98 124.46 0)
			(effects
				(font
					(size 1.27 1.27)
					(thickness 0.15)
				)
				(justify left bottom)
				(hide yes)
			)
		)
		(property "Author" "Antmicro"
			(at 93.98 127 0)
			(effects
				(font
					(size 1.27 1.27)
					(thickness 0.15)
				)
				(justify left bottom)
				(hide yes)
			)
		)
		(property "Tolerance" "~"
			(at 93.98 109.22 0)
			(effects
				(font
					(size 1.27 1.27)
				)
				(justify left bottom)
				(hide yes)
			)
		)
		(property "Current" "1A"
			(at 93.98 129.54 0)
			(effects
				(font
					(size 1.27 1.27)
					(thickness 0.15)
				)
				(justify left bottom)
				(hide yes)
			)
		)
		(pin "1"
		)
		(pin "2"
		)
		(instances
			(project "jetson-orin-baseboard"
				(path ""
					(reference "R71")
					(unit 1)
				)
			)
		)
	)
	(symbol
		(lib_name "GND_3")
		(lib_id "antmicropower:GND")
		(at 337.82 198.12 0)
		(mirror y)
		(unit 1)
		(exclude_from_sim no)
		(in_bom yes)
		(on_board yes)
		(dnp no)
		(property "Reference" "#PWR0100"
			(at 337.82 204.47 0)
			(effects
				(font
					(size 1.27 1.27)
				)
				(justify left bottom)
				(hide yes)
			)
		)
		(property "Value" "GND"
			(at 337.82 201.93 0)
			(effects
				(font
					(size 1.27 1.27)
					(thickness 0.15)
				)
			)
		)
		(property "Footprint" ""
			(at 328.93 205.74 0)
			(effects
				(font
					(size 1.27 1.27)
					(thickness 0.15)
				)
				(justify left bottom)
				(hide yes)
			)
		)
		(property "Datasheet" ""
			(at 328.93 210.82 0)
			(effects
				(font
					(size 1.27 1.27)
					(thickness 0.15)
				)
				(justify left bottom)
				(hide yes)
			)
		)
		(property "Description" ""
			(at 337.82 198.12 0)
			(effects
				(font
					(size 1.27 1.27)
				)
				(hide yes)
			)
		)
		(property "Author" "Antmicro"
			(at 328.93 205.74 0)
			(effects
				(font
					(size 1.27 1.27)
					(thickness 0.15)
				)
				(justify left bottom)
				(hide yes)
			)
		)
		(property "License" "Apache-2.0"
			(at 328.93 208.28 0)
			(effects
				(font
					(size 1.27 1.27)
					(thickness 0.15)
				)
				(justify left bottom)
				(hide yes)
			)
		)
		(pin "1"
		)
		(instances
			(project "jetson-orin-baseboard"
				(path ""
					(reference "#PWR0100")
					(unit 1)
				)
			)
		)
	)
	(symbol
		(lib_name "GND_3")
		(lib_id "antmicropower:GND")
		(at 340.36 66.04 0)
		(mirror y)
		(unit 1)
		(exclude_from_sim no)
		(in_bom yes)
		(on_board yes)
		(dnp no)
		(property "Reference" "#PWR0102"
			(at 340.36 72.39 0)
			(effects
				(font
					(size 1.27 1.27)
				)
				(justify left bottom)
				(hide yes)
			)
		)
		(property "Value" "GND"
			(at 340.36 69.85 0)
			(effects
				(font
					(size 1.27 1.27)
					(thickness 0.15)
				)
			)
		)
		(property "Footprint" ""
			(at 331.47 73.66 0)
			(effects
				(font
					(size 1.27 1.27)
					(thickness 0.15)
				)
				(justify left bottom)
				(hide yes)
			)
		)
		(property "Datasheet" ""
			(at 331.47 78.74 0)
			(effects
				(font
					(size 1.27 1.27)
					(thickness 0.15)
				)
				(justify left bottom)
				(hide yes)
			)
		)
		(property "Description" ""
			(at 340.36 66.04 0)
			(effects
				(font
					(size 1.27 1.27)
				)
				(hide yes)
			)
		)
		(property "Author" "Antmicro"
			(at 331.47 73.66 0)
			(effects
				(font
					(size 1.27 1.27)
					(thickness 0.15)
				)
				(justify left bottom)
				(hide yes)
			)
		)
		(property "License" "Apache-2.0"
			(at 331.47 76.2 0)
			(effects
				(font
					(size 1.27 1.27)
					(thickness 0.15)
				)
				(justify left bottom)
				(hide yes)
			)
		)
		(pin "1"
		)
		(instances
			(project "jetson-orin-baseboard"
				(path ""
					(reference "#PWR0102")
					(unit 1)
				)
			)
		)
	)
	(symbol
		(lib_name "GND_3")
		(lib_id "antmicropower:GND")
		(at 200.66 73.66 0)
		(mirror y)
		(unit 1)
		(exclude_from_sim no)
		(in_bom yes)
		(on_board yes)
		(dnp no)
		(property "Reference" "#PWR078"
			(at 200.66 80.01 0)
			(effects
				(font
					(size 1.27 1.27)
				)
				(justify left bottom)
				(hide yes)
			)
		)
		(property "Value" "GND"
			(at 200.66 77.47 0)
			(effects
				(font
					(size 1.27 1.27)
					(thickness 0.15)
				)
			)
		)
		(property "Footprint" ""
			(at 191.77 81.28 0)
			(effects
				(font
					(size 1.27 1.27)
					(thickness 0.15)
				)
				(justify left bottom)
				(hide yes)
			)
		)
		(property "Datasheet" ""
			(at 191.77 86.36 0)
			(effects
				(font
					(size 1.27 1.27)
					(thickness 0.15)
				)
				(justify left bottom)
				(hide yes)
			)
		)
		(property "Description" ""
			(at 200.66 73.66 0)
			(effects
				(font
					(size 1.27 1.27)
				)
				(hide yes)
			)
		)
		(property "Author" "Antmicro"
			(at 191.77 81.28 0)
			(effects
				(font
					(size 1.27 1.27)
					(thickness 0.15)
				)
				(justify left bottom)
				(hide yes)
			)
		)
		(property "License" "Apache-2.0"
			(at 191.77 83.82 0)
			(effects
				(font
					(size 1.27 1.27)
					(thickness 0.15)
				)
				(justify left bottom)
				(hide yes)
			)
		)
		(pin "1"
		)
		(instances
			(project "jetson-orin-baseboard"
				(path ""
					(reference "#PWR078")
					(unit 1)
				)
			)
		)
	)
	(symbol
		(lib_id "antmicroCapacitors0402:C_100n_0402")
		(at 275.59 124.46 0)
		(unit 1)
		(exclude_from_sim no)
		(in_bom yes)
		(on_board yes)
		(dnp no)
		(property "Reference" "C63"
			(at 279.4 123.825 0)
			(effects
				(font
					(size 1.27 1.27)
				)
				(justify left bottom)
			)
		)
		(property "Value" "C_100n_0402"
			(at 295.91 134.62 0)
			(effects
				(font
					(size 1.27 1.27)
					(thickness 0.15)
				)
				(justify left bottom)
				(hide yes)
			)
		)
		(property "Footprint" "antmicro-footprints:C_0402_1005Metric"
			(at 295.91 137.16 0)
			(effects
				(font
					(size 1.27 1.27)
					(thickness 0.15)
				)
				(justify left bottom)
				(hide yes)
			)
		)
		(property "Datasheet" "https://www.murata.com/products/productdetail?partno=GRM155R61H104KE14%23"
			(at 295.91 139.7 0)
			(effects
				(font
					(size 1.27 1.27)
					(thickness 0.15)
				)
				(justify left bottom)
				(hide yes)
			)
		)
		(property "Description" ""
			(at 275.59 124.46 0)
			(effects
				(font
					(size 1.27 1.27)
				)
				(hide yes)
			)
		)
		(property "Manufacturer" "Murata"
			(at 295.91 144.78 0)
			(effects
				(font
					(size 1.27 1.27)
					(thickness 0.15)
				)
				(justify left bottom)
				(hide yes)
			)
		)
		(property "MPN" "GRM155R61H104KE14D"
			(at 295.91 142.24 0)
			(effects
				(font
					(size 1.27 1.27)
					(thickness 0.15)
				)
				(justify left bottom)
				(hide yes)
			)
		)
		(property "Val" "100n"
			(at 271.78 126.365 0)
			(effects
				(font
					(size 1.27 1.27)
					(thickness 0.15)
				)
				(justify left bottom)
			)
		)
		(property "License" "Apache-2.0"
			(at 295.91 147.32 0)
			(effects
				(font
					(size 1.27 1.27)
					(thickness 0.15)
				)
				(justify left bottom)
				(hide yes)
			)
		)
		(property "Author" "Antmicro"
			(at 295.91 149.86 0)
			(effects
				(font
					(size 1.27 1.27)
					(thickness 0.15)
				)
				(justify left bottom)
				(hide yes)
			)
		)
		(property "Voltage" "50V"
			(at 295.91 152.4 0)
			(effects
				(font
					(size 1.27 1.27)
				)
				(justify left bottom)
				(hide yes)
			)
		)
		(property "Dielectric" "X5R"
			(at 295.91 154.94 0)
			(effects
				(font
					(size 1.27 1.27)
				)
				(justify left bottom)
				(hide yes)
			)
		)
		(pin "1"
		)
		(pin "2"
		)
		(instances
			(project "jetson-orin-baseboard"
				(path ""
					(reference "C63")
					(unit 1)
				)
			)
		)
	)
	(symbol
		(lib_name "C_100n_0402_3")
		(lib_id "antmicroCapacitors0402:C_100n_0402")
		(at 35.56 194.31 90)
		(mirror x)
		(unit 1)
		(exclude_from_sim no)
		(in_bom yes)
		(on_board yes)
		(dnp no)
		(fields_autoplaced yes)
		(property "Reference" "C29"
			(at 38.1 195.5863 90)
			(effects
				(font
					(size 1.27 1.27)
				)
				(justify right)
			)
		)
		(property "Value" "C_100n_0402"
			(at 45.72 214.63 0)
			(effects
				(font
					(size 1.27 1.27)
					(thickness 0.15)
				)
				(justify left bottom)
				(hide yes)
			)
		)
		(property "Footprint" "antmicro-footprints:C_0402_1005Metric"
			(at 48.26 214.63 0)
			(effects
				(font
					(size 1.27 1.27)
					(thickness 0.15)
				)
				(justify left bottom)
				(hide yes)
			)
		)
		(property "Datasheet" "https://www.murata.com/products/productdetail?partno=GRM155R61H104KE14%23"
			(at 50.8 214.63 0)
			(effects
				(font
					(size 1.27 1.27)
					(thickness 0.15)
				)
				(justify left bottom)
				(hide yes)
			)
		)
		(property "Description" ""
			(at 35.56 194.31 0)
			(effects
				(font
					(size 1.27 1.27)
				)
				(hide yes)
			)
		)
		(property "Manufacturer" "Murata"
			(at 55.88 214.63 0)
			(effects
				(font
					(size 1.27 1.27)
					(thickness 0.15)
				)
				(justify left bottom)
				(hide yes)
			)
		)
		(property "MPN" "GRM155R61H104KE14D"
			(at 53.34 214.63 0)
			(effects
				(font
					(size 1.27 1.27)
					(thickness 0.15)
				)
				(justify left bottom)
				(hide yes)
			)
		)
		(property "Val" "100n"
			(at 38.1 198.1263 90)
			(effects
				(font
					(size 1.27 1.27)
					(thickness 0.15)
				)
				(justify right)
			)
		)
		(property "License" "Apache-2.0"
			(at 58.42 214.63 0)
			(effects
				(font
					(size 1.27 1.27)
					(thickness 0.15)
				)
				(justify left bottom)
				(hide yes)
			)
		)
		(property "Author" "Antmicro"
			(at 60.96 214.63 0)
			(effects
				(font
					(size 1.27 1.27)
					(thickness 0.15)
				)
				(justify left bottom)
				(hide yes)
			)
		)
		(property "Voltage" "50V"
			(at 63.5 214.63 0)
			(effects
				(font
					(size 1.27 1.27)
				)
				(justify left bottom)
				(hide yes)
			)
		)
		(property "Dielectric" "X5R"
			(at 66.04 214.63 0)
			(effects
				(font
					(size 1.27 1.27)
				)
				(justify left bottom)
				(hide yes)
			)
		)
		(pin "1"
		)
		(pin "2"
		)
		(instances
			(project "jetson-orin-baseboard"
				(path ""
					(reference "C29")
					(unit 1)
				)
			)
		)
	)
	(symbol
		(lib_name "GND_3")
		(lib_id "antmicropower:GND")
		(at 50.8 111.76 0)
		(mirror y)
		(unit 1)
		(exclude_from_sim no)
		(in_bom yes)
		(on_board yes)
		(dnp no)
		(property "Reference" "#PWR057"
			(at 50.8 118.11 0)
			(effects
				(font
					(size 1.27 1.27)
				)
				(justify left bottom)
				(hide yes)
			)
		)
		(property "Value" "GND"
			(at 50.8 115.57 0)
			(effects
				(font
					(size 1.27 1.27)
					(thickness 0.15)
				)
			)
		)
		(property "Footprint" ""
			(at 41.91 119.38 0)
			(effects
				(font
					(size 1.27 1.27)
					(thickness 0.15)
				)
				(justify left bottom)
				(hide yes)
			)
		)
		(property "Datasheet" ""
			(at 41.91 124.46 0)
			(effects
				(font
					(size 1.27 1.27)
					(thickness 0.15)
				)
				(justify left bottom)
				(hide yes)
			)
		)
		(property "Description" ""
			(at 50.8 111.76 0)
			(effects
				(font
					(size 1.27 1.27)
				)
				(hide yes)
			)
		)
		(property "Author" "Antmicro"
			(at 41.91 119.38 0)
			(effects
				(font
					(size 1.27 1.27)
					(thickness 0.15)
				)
				(justify left bottom)
				(hide yes)
			)
		)
		(property "License" "Apache-2.0"
			(at 41.91 121.92 0)
			(effects
				(font
					(size 1.27 1.27)
					(thickness 0.15)
				)
				(justify left bottom)
				(hide yes)
			)
		)
		(pin "1"
		)
		(instances
			(project "jetson-orin-baseboard"
				(path ""
					(reference "#PWR057")
					(unit 1)
				)
			)
		)
	)
	(symbol
		(lib_name "GND_3")
		(lib_id "antmicropower:GND")
		(at 33.02 46.99 0)
		(mirror y)
		(unit 1)
		(exclude_from_sim no)
		(in_bom yes)
		(on_board yes)
		(dnp no)
		(property "Reference" "#PWR081"
			(at 33.02 53.34 0)
			(effects
				(font
					(size 1.27 1.27)
				)
				(justify left bottom)
				(hide yes)
			)
		)
		(property "Value" "GND"
			(at 33.02 50.8 0)
			(effects
				(font
					(size 1.27 1.27)
					(thickness 0.15)
				)
			)
		)
		(property "Footprint" ""
			(at 24.13 54.61 0)
			(effects
				(font
					(size 1.27 1.27)
					(thickness 0.15)
				)
				(justify left bottom)
				(hide yes)
			)
		)
		(property "Datasheet" ""
			(at 24.13 59.69 0)
			(effects
				(font
					(size 1.27 1.27)
					(thickness 0.15)
				)
				(justify left bottom)
				(hide yes)
			)
		)
		(property "Description" ""
			(at 33.02 46.99 0)
			(effects
				(font
					(size 1.27 1.27)
				)
				(hide yes)
			)
		)
		(property "Author" "Antmicro"
			(at 24.13 54.61 0)
			(effects
				(font
					(size 1.27 1.27)
					(thickness 0.15)
				)
				(justify left bottom)
				(hide yes)
			)
		)
		(property "License" "Apache-2.0"
			(at 24.13 57.15 0)
			(effects
				(font
					(size 1.27 1.27)
					(thickness 0.15)
				)
				(justify left bottom)
				(hide yes)
			)
		)
		(pin "1"
		)
		(instances
			(project "jetson-orin-baseboard"
				(path ""
					(reference "#PWR081")
					(unit 1)
				)
			)
		)
	)
	(symbol
		(lib_name "GND_3")
		(lib_id "antmicropower:GND")
		(at 273.05 91.44 0)
		(mirror y)
		(unit 1)
		(exclude_from_sim no)
		(in_bom yes)
		(on_board yes)
		(dnp no)
		(property "Reference" "#PWR086"
			(at 273.05 97.79 0)
			(effects
				(font
					(size 1.27 1.27)
				)
				(justify left bottom)
				(hide yes)
			)
		)
		(property "Value" "GND"
			(at 273.05 95.25 0)
			(effects
				(font
					(size 1.27 1.27)
					(thickness 0.15)
				)
			)
		)
		(property "Footprint" ""
			(at 264.16 99.06 0)
			(effects
				(font
					(size 1.27 1.27)
					(thickness 0.15)
				)
				(justify left bottom)
				(hide yes)
			)
		)
		(property "Datasheet" ""
			(at 264.16 104.14 0)
			(effects
				(font
					(size 1.27 1.27)
					(thickness 0.15)
				)
				(justify left bottom)
				(hide yes)
			)
		)
		(property "Description" ""
			(at 273.05 91.44 0)
			(effects
				(font
					(size 1.27 1.27)
				)
				(hide yes)
			)
		)
		(property "Author" "Antmicro"
			(at 264.16 99.06 0)
			(effects
				(font
					(size 1.27 1.27)
					(thickness 0.15)
				)
				(justify left bottom)
				(hide yes)
			)
		)
		(property "License" "Apache-2.0"
			(at 264.16 101.6 0)
			(effects
				(font
					(size 1.27 1.27)
					(thickness 0.15)
				)
				(justify left bottom)
				(hide yes)
			)
		)
		(pin "1"
		)
		(instances
			(project "jetson-orin-baseboard"
				(path ""
					(reference "#PWR086")
					(unit 1)
				)
			)
		)
	)
	(symbol
		(lib_name "GND_3")
		(lib_id "antmicropower:GND")
		(at 327.66 198.12 0)
		(mirror y)
		(unit 1)
		(exclude_from_sim no)
		(in_bom yes)
		(on_board yes)
		(dnp no)
		(property "Reference" "#PWR0101"
			(at 327.66 204.47 0)
			(effects
				(font
					(size 1.27 1.27)
				)
				(justify left bottom)
				(hide yes)
			)
		)
		(property "Value" "GND"
			(at 327.66 201.93 0)
			(effects
				(font
					(size 1.27 1.27)
					(thickness 0.15)
				)
			)
		)
		(property "Footprint" ""
			(at 318.77 205.74 0)
			(effects
				(font
					(size 1.27 1.27)
					(thickness 0.15)
				)
				(justify left bottom)
				(hide yes)
			)
		)
		(property "Datasheet" ""
			(at 318.77 210.82 0)
			(effects
				(font
					(size 1.27 1.27)
					(thickness 0.15)
				)
				(justify left bottom)
				(hide yes)
			)
		)
		(property "Description" ""
			(at 327.66 198.12 0)
			(effects
				(font
					(size 1.27 1.27)
				)
				(hide yes)
			)
		)
		(property "Author" "Antmicro"
			(at 318.77 205.74 0)
			(effects
				(font
					(size 1.27 1.27)
					(thickness 0.15)
				)
				(justify left bottom)
				(hide yes)
			)
		)
		(property "License" "Apache-2.0"
			(at 318.77 208.28 0)
			(effects
				(font
					(size 1.27 1.27)
					(thickness 0.15)
				)
				(justify left bottom)
				(hide yes)
			)
		)
		(pin "1"
		)
		(instances
			(project "jetson-orin-baseboard"
				(path ""
					(reference "#PWR0101")
					(unit 1)
				)
			)
		)
	)
	(symbol
		(lib_id "antmicroCapacitors0402:C_100n_0402")
		(at 275.59 109.22 0)
		(unit 1)
		(exclude_from_sim no)
		(in_bom yes)
		(on_board yes)
		(dnp no)
		(property "Reference" "C62"
			(at 279.4 108.585 0)
			(effects
				(font
					(size 1.27 1.27)
				)
				(justify left bottom)
			)
		)
		(property "Value" "C_100n_0402"
			(at 295.91 119.38 0)
			(effects
				(font
					(size 1.27 1.27)
					(thickness 0.15)
				)
				(justify left bottom)
				(hide yes)
			)
		)
		(property "Footprint" "antmicro-footprints:C_0402_1005Metric"
			(at 295.91 121.92 0)
			(effects
				(font
					(size 1.27 1.27)
					(thickness 0.15)
				)
				(justify left bottom)
				(hide yes)
			)
		)
		(property "Datasheet" "https://www.murata.com/products/productdetail?partno=GRM155R61H104KE14%23"
			(at 295.91 124.46 0)
			(effects
				(font
					(size 1.27 1.27)
					(thickness 0.15)
				)
				(justify left bottom)
				(hide yes)
			)
		)
		(property "Description" ""
			(at 275.59 109.22 0)
			(effects
				(font
					(size 1.27 1.27)
				)
				(hide yes)
			)
		)
		(property "Manufacturer" "Murata"
			(at 295.91 129.54 0)
			(effects
				(font
					(size 1.27 1.27)
					(thickness 0.15)
				)
				(justify left bottom)
				(hide yes)
			)
		)
		(property "MPN" "GRM155R61H104KE14D"
			(at 295.91 127 0)
			(effects
				(font
					(size 1.27 1.27)
					(thickness 0.15)
				)
				(justify left bottom)
				(hide yes)
			)
		)
		(property "Val" "100n"
			(at 271.78 111.125 0)
			(effects
				(font
					(size 1.27 1.27)
					(thickness 0.15)
				)
				(justify left bottom)
			)
		)
		(property "License" "Apache-2.0"
			(at 295.91 132.08 0)
			(effects
				(font
					(size 1.27 1.27)
					(thickness 0.15)
				)
				(justify left bottom)
				(hide yes)
			)
		)
		(property "Author" "Antmicro"
			(at 295.91 134.62 0)
			(effects
				(font
					(size 1.27 1.27)
					(thickness 0.15)
				)
				(justify left bottom)
				(hide yes)
			)
		)
		(property "Voltage" "50V"
			(at 295.91 137.16 0)
			(effects
				(font
					(size 1.27 1.27)
				)
				(justify left bottom)
				(hide yes)
			)
		)
		(property "Dielectric" "X5R"
			(at 295.91 139.7 0)
			(effects
				(font
					(size 1.27 1.27)
				)
				(justify left bottom)
				(hide yes)
			)
		)
		(pin "1"
		)
		(pin "2"
		)
		(instances
			(project "jetson-orin-baseboard"
				(path ""
					(reference "C62")
					(unit 1)
				)
			)
		)
	)
	(symbol
		(lib_name "GND_3")
		(lib_id "antmicropower:GND")
		(at 71.12 148.59 0)
		(mirror y)
		(unit 1)
		(exclude_from_sim no)
		(in_bom yes)
		(on_board yes)
		(dnp no)
		(property "Reference" "#PWR060"
			(at 71.12 154.94 0)
			(effects
				(font
					(size 1.27 1.27)
				)
				(justify left bottom)
				(hide yes)
			)
		)
		(property "Value" "GND"
			(at 71.12 152.4 0)
			(effects
				(font
					(size 1.27 1.27)
					(thickness 0.15)
				)
			)
		)
		(property "Footprint" ""
			(at 62.23 156.21 0)
			(effects
				(font
					(size 1.27 1.27)
					(thickness 0.15)
				)
				(justify left bottom)
				(hide yes)
			)
		)
		(property "Datasheet" ""
			(at 62.23 161.29 0)
			(effects
				(font
					(size 1.27 1.27)
					(thickness 0.15)
				)
				(justify left bottom)
				(hide yes)
			)
		)
		(property "Description" ""
			(at 71.12 148.59 0)
			(effects
				(font
					(size 1.27 1.27)
				)
				(hide yes)
			)
		)
		(property "Author" "Antmicro"
			(at 62.23 156.21 0)
			(effects
				(font
					(size 1.27 1.27)
					(thickness 0.15)
				)
				(justify left bottom)
				(hide yes)
			)
		)
		(property "License" "Apache-2.0"
			(at 62.23 158.75 0)
			(effects
				(font
					(size 1.27 1.27)
					(thickness 0.15)
				)
				(justify left bottom)
				(hide yes)
			)
		)
		(pin "1"
		)
		(instances
			(project "jetson-orin-baseboard"
				(path ""
					(reference "#PWR060")
					(unit 1)
				)
			)
		)
	)
	(symbol
		(lib_id "antmicroResistors0402:R_27R_0402")
		(at 330.2 222.25 0)
		(unit 1)
		(exclude_from_sim no)
		(in_bom yes)
		(on_board yes)
		(dnp no)
		(property "Reference" "R117"
			(at 335.28 221.615 0)
			(effects
				(font
					(size 1.27 1.27)
				)
				(justify left bottom)
			)
		)
		(property "Value" "R_27R_0402"
			(at 350.52 234.95 0)
			(effects
				(font
					(size 1.27 1.27)
					(thickness 0.15)
				)
				(justify left bottom)
				(hide yes)
			)
		)
		(property "Footprint" "antmicro-footprints:R_0402_1005Metric"
			(at 350.52 237.49 0)
			(effects
				(font
					(size 1.27 1.27)
					(thickness 0.15)
				)
				(justify left bottom)
				(hide yes)
			)
		)
		(property "Datasheet" "https://www.bourns.com/docs/product-datasheets/cr.pdf"
			(at 350.52 240.03 0)
			(effects
				(font
					(size 1.27 1.27)
					(thickness 0.15)
				)
				(justify left bottom)
				(hide yes)
			)
		)
		(property "Description" ""
			(at 330.2 222.25 0)
			(effects
				(font
					(size 1.27 1.27)
				)
				(hide yes)
			)
		)
		(property "Manufacturer" "Bourns"
			(at 350.52 245.11 0)
			(effects
				(font
					(size 1.27 1.27)
					(thickness 0.15)
				)
				(justify left bottom)
				(hide yes)
			)
		)
		(property "MPN" "CR0402-FX-27R0GLF"
			(at 350.52 242.57 0)
			(effects
				(font
					(size 1.27 1.27)
					(thickness 0.15)
				)
				(justify left bottom)
				(hide yes)
			)
		)
		(property "Val" "27R"
			(at 326.39 221.615 0)
			(effects
				(font
					(size 1.27 1.27)
					(thickness 0.15)
				)
				(justify left bottom)
			)
		)
		(property "License" "Apache-2.0"
			(at 350.52 247.65 0)
			(effects
				(font
					(size 1.27 1.27)
					(thickness 0.15)
				)
				(justify left bottom)
				(hide yes)
			)
		)
		(property "Author" "Antmicro"
			(at 350.52 250.19 0)
			(effects
				(font
					(size 1.27 1.27)
					(thickness 0.15)
				)
				(justify left bottom)
				(hide yes)
			)
		)
		(property "Tolerance" "1%"
			(at 350.52 232.41 0)
			(effects
				(font
					(size 1.27 1.27)
				)
				(justify left bottom)
				(hide yes)
			)
		)
		(pin "1"
		)
		(pin "2"
		)
		(instances
			(project "jetson-orin-baseboard"
				(path ""
					(reference "R117")
					(unit 1)
				)
			)
		)
	)
	(symbol
		(lib_name "C_100n_0402_7")
		(lib_id "antmicroCapacitors0402:C_100n_0402")
		(at 187.96 243.84 90)
		(mirror x)
		(unit 1)
		(exclude_from_sim no)
		(in_bom yes)
		(on_board yes)
		(dnp no)
		(fields_autoplaced yes)
		(property "Reference" "C53"
			(at 185.42 245.1163 90)
			(effects
				(font
					(size 1.27 1.27)
				)
				(justify left)
			)
		)
		(property "Value" "C_100n_0402"
			(at 198.12 264.16 0)
			(effects
				(font
					(size 1.27 1.27)
					(thickness 0.15)
				)
				(justify left bottom)
				(hide yes)
			)
		)
		(property "Footprint" "antmicro-footprints:C_0402_1005Metric"
			(at 200.66 264.16 0)
			(effects
				(font
					(size 1.27 1.27)
					(thickness 0.15)
				)
				(justify left bottom)
				(hide yes)
			)
		)
		(property "Datasheet" "https://www.murata.com/products/productdetail?partno=GRM155R61H104KE14%23"
			(at 203.2 264.16 0)
			(effects
				(font
					(size 1.27 1.27)
					(thickness 0.15)
				)
				(justify left bottom)
				(hide yes)
			)
		)
		(property "Description" ""
			(at 187.96 243.84 0)
			(effects
				(font
					(size 1.27 1.27)
				)
				(hide yes)
			)
		)
		(property "MPN" "GRM155R61H104KE14D"
			(at 205.74 264.16 0)
			(effects
				(font
					(size 1.27 1.27)
					(thickness 0.15)
				)
				(justify left bottom)
				(hide yes)
			)
		)
		(property "Manufacturer" "Murata"
			(at 208.28 264.16 0)
			(effects
				(font
					(size 1.27 1.27)
					(thickness 0.15)
				)
				(justify left bottom)
				(hide yes)
			)
		)
		(property "Val" "100n"
			(at 185.42 247.6563 90)
			(effects
				(font
					(size 1.27 1.27)
					(thickness 0.15)
				)
				(justify left)
			)
		)
		(property "License" "Apache-2.0"
			(at 210.82 264.16 0)
			(effects
				(font
					(size 1.27 1.27)
					(thickness 0.15)
				)
				(justify left bottom)
				(hide yes)
			)
		)
		(property "Author" "Antmicro"
			(at 213.36 264.16 0)
			(effects
				(font
					(size 1.27 1.27)
					(thickness 0.15)
				)
				(justify left bottom)
				(hide yes)
			)
		)
		(property "Voltage" "50V"
			(at 215.9 264.16 0)
			(effects
				(font
					(size 1.27 1.27)
				)
				(justify left bottom)
				(hide yes)
			)
		)
		(property "Dielectric" "X5R"
			(at 218.44 264.16 0)
			(effects
				(font
					(size 1.27 1.27)
				)
				(justify left bottom)
				(hide yes)
			)
		)
		(pin "1"
		)
		(pin "2"
		)
		(instances
			(project "jetson-orin-baseboard"
				(path ""
					(reference "C53")
					(unit 1)
				)
			)
		)
	)
	(symbol
		(lib_id "antmicroCapacitors0402:C_100n_0402")
		(at 179.07 67.31 90)
		(mirror x)
		(unit 1)
		(exclude_from_sim no)
		(in_bom yes)
		(on_board yes)
		(dnp no)
		(fields_autoplaced yes)
		(property "Reference" "C37"
			(at 181.61 68.5863 90)
			(effects
				(font
					(size 1.27 1.27)
				)
				(justify right)
			)
		)
		(property "Value" "C_100n_0402"
			(at 189.23 87.63 0)
			(effects
				(font
					(size 1.27 1.27)
					(thickness 0.15)
				)
				(justify left bottom)
				(hide yes)
			)
		)
		(property "Footprint" "antmicro-footprints:C_0402_1005Metric"
			(at 191.77 87.63 0)
			(effects
				(font
					(size 1.27 1.27)
					(thickness 0.15)
				)
				(justify left bottom)
				(hide yes)
			)
		)
		(property "Datasheet" "https://www.murata.com/products/productdetail?partno=GRM155R61H104KE14%23"
			(at 194.31 87.63 0)
			(effects
				(font
					(size 1.27 1.27)
					(thickness 0.15)
				)
				(justify left bottom)
				(hide yes)
			)
		)
		(property "Description" ""
			(at 179.07 67.31 0)
			(effects
				(font
					(size 1.27 1.27)
				)
				(hide yes)
			)
		)
		(property "Manufacturer" "Murata"
			(at 199.39 87.63 0)
			(effects
				(font
					(size 1.27 1.27)
					(thickness 0.15)
				)
				(justify left bottom)
				(hide yes)
			)
		)
		(property "MPN" "GRM155R61H104KE14D"
			(at 196.85 87.63 0)
			(effects
				(font
					(size 1.27 1.27)
					(thickness 0.15)
				)
				(justify left bottom)
				(hide yes)
			)
		)
		(property "Val" "100n"
			(at 181.61 71.1263 90)
			(effects
				(font
					(size 1.27 1.27)
					(thickness 0.15)
				)
				(justify right)
			)
		)
		(property "License" "Apache-2.0"
			(at 201.93 87.63 0)
			(effects
				(font
					(size 1.27 1.27)
					(thickness 0.15)
				)
				(justify left bottom)
				(hide yes)
			)
		)
		(property "Author" "Antmicro"
			(at 204.47 87.63 0)
			(effects
				(font
					(size 1.27 1.27)
					(thickness 0.15)
				)
				(justify left bottom)
				(hide yes)
			)
		)
		(property "Voltage" "50V"
			(at 207.01 87.63 0)
			(effects
				(font
					(size 1.27 1.27)
				)
				(justify left bottom)
				(hide yes)
			)
		)
		(property "Dielectric" "X5R"
			(at 209.55 87.63 0)
			(effects
				(font
					(size 1.27 1.27)
				)
				(justify left bottom)
				(hide yes)
			)
		)
		(pin "1"
		)
		(pin "2"
		)
		(instances
			(project "jetson-orin-baseboard"
				(path ""
					(reference "C37")
					(unit 1)
				)
			)
		)
	)
	(symbol
		(lib_name "GND_3")
		(lib_id "antmicropower:GND")
		(at 130.81 251.46 0)
		(mirror y)
		(unit 1)
		(exclude_from_sim no)
		(in_bom yes)
		(on_board yes)
		(dnp no)
		(property "Reference" "#PWR0365"
			(at 130.81 257.81 0)
			(effects
				(font
					(size 1.27 1.27)
				)
				(justify left bottom)
				(hide yes)
			)
		)
		(property "Value" "GND"
			(at 130.81 255.27 0)
			(effects
				(font
					(size 1.27 1.27)
					(thickness 0.15)
				)
			)
		)
		(property "Footprint" ""
			(at 121.92 259.08 0)
			(effects
				(font
					(size 1.27 1.27)
					(thickness 0.15)
				)
				(justify left bottom)
				(hide yes)
			)
		)
		(property "Datasheet" ""
			(at 121.92 264.16 0)
			(effects
				(font
					(size 1.27 1.27)
					(thickness 0.15)
				)
				(justify left bottom)
				(hide yes)
			)
		)
		(property "Description" ""
			(at 130.81 251.46 0)
			(effects
				(font
					(size 1.27 1.27)
				)
				(hide yes)
			)
		)
		(property "Author" "Antmicro"
			(at 121.92 259.08 0)
			(effects
				(font
					(size 1.27 1.27)
					(thickness 0.15)
				)
				(justify left bottom)
				(hide yes)
			)
		)
		(property "License" "Apache-2.0"
			(at 121.92 261.62 0)
			(effects
				(font
					(size 1.27 1.27)
					(thickness 0.15)
				)
				(justify left bottom)
				(hide yes)
			)
		)
		(pin "1"
		)
		(instances
			(project "jetson-orin-baseboard"
				(path ""
					(reference "#PWR0365")
					(unit 1)
				)
			)
		)
	)
	(symbol
		(lib_name "GND_3")
		(lib_id "antmicropower:GND")
		(at 229.87 219.71 0)
		(mirror y)
		(unit 1)
		(exclude_from_sim no)
		(in_bom yes)
		(on_board yes)
		(dnp no)
		(property "Reference" "#PWR073"
			(at 229.87 226.06 0)
			(effects
				(font
					(size 1.27 1.27)
				)
				(justify left bottom)
				(hide yes)
			)
		)
		(property "Value" "GND"
			(at 229.87 223.52 0)
			(effects
				(font
					(size 1.27 1.27)
					(thickness 0.15)
				)
			)
		)
		(property "Footprint" ""
			(at 220.98 227.33 0)
			(effects
				(font
					(size 1.27 1.27)
					(thickness 0.15)
				)
				(justify left bottom)
				(hide yes)
			)
		)
		(property "Datasheet" ""
			(at 220.98 232.41 0)
			(effects
				(font
					(size 1.27 1.27)
					(thickness 0.15)
				)
				(justify left bottom)
				(hide yes)
			)
		)
		(property "Description" ""
			(at 229.87 219.71 0)
			(effects
				(font
					(size 1.27 1.27)
				)
				(hide yes)
			)
		)
		(property "Author" "Antmicro"
			(at 220.98 227.33 0)
			(effects
				(font
					(size 1.27 1.27)
					(thickness 0.15)
				)
				(justify left bottom)
				(hide yes)
			)
		)
		(property "License" "Apache-2.0"
			(at 220.98 229.87 0)
			(effects
				(font
					(size 1.27 1.27)
					(thickness 0.15)
				)
				(justify left bottom)
				(hide yes)
			)
		)
		(pin "1"
		)
		(instances
			(project "jetson-orin-baseboard"
				(path ""
					(reference "#PWR073")
					(unit 1)
				)
			)
		)
	)
	(symbol
		(lib_id "antmicroResistors0402:R_1k_0402")
		(at 262.89 144.78 0)
		(unit 1)
		(exclude_from_sim no)
		(in_bom no)
		(on_board yes)
		(dnp yes)
		(property "Reference" "R87"
			(at 268.605 144.145 0)
			(effects
				(font
					(size 1.27 1.27)
				)
				(justify left bottom)
			)
		)
		(property "Value" "R_1k_0402"
			(at 283.21 157.48 0)
			(effects
				(font
					(size 1.27 1.27)
					(thickness 0.15)
				)
				(justify left bottom)
				(hide yes)
			)
		)
		(property "Footprint" "antmicro-footprints:R_0402_1005Metric"
			(at 283.21 160.02 0)
			(effects
				(font
					(size 1.27 1.27)
					(thickness 0.15)
				)
				(justify left bottom)
				(hide yes)
			)
		)
		(property "Datasheet" "https://www.bourns.com/docs/product-datasheets/cr.pdf"
			(at 283.21 162.56 0)
			(effects
				(font
					(size 1.27 1.27)
					(thickness 0.15)
				)
				(justify left bottom)
				(hide yes)
			)
		)
		(property "Description" ""
			(at 262.89 144.78 0)
			(effects
				(font
					(size 1.27 1.27)
				)
				(hide yes)
			)
		)
		(property "Manufacturer" "Bourns"
			(at 283.21 167.64 0)
			(effects
				(font
					(size 1.27 1.27)
					(thickness 0.15)
				)
				(justify left bottom)
				(hide yes)
			)
		)
		(property "MPN" "CR0402-FX-1001GLF"
			(at 283.21 165.1 0)
			(effects
				(font
					(size 1.27 1.27)
					(thickness 0.15)
				)
				(justify left bottom)
				(hide yes)
			)
		)
		(property "Val" "1k"
			(at 260.35 144.145 0)
			(effects
				(font
					(size 1.27 1.27)
					(thickness 0.15)
				)
				(justify left bottom)
			)
		)
		(property "License" "Apache-2.0"
			(at 283.21 170.18 0)
			(effects
				(font
					(size 1.27 1.27)
					(thickness 0.15)
				)
				(justify left bottom)
				(hide yes)
			)
		)
		(property "Author" "Antmicro"
			(at 283.21 172.72 0)
			(effects
				(font
					(size 1.27 1.27)
					(thickness 0.15)
				)
				(justify left bottom)
				(hide yes)
			)
		)
		(property "Tolerance" "1%"
			(at 283.21 154.94 0)
			(effects
				(font
					(size 1.27 1.27)
				)
				(justify left bottom)
				(hide yes)
			)
		)
		(pin "1"
		)
		(pin "2"
		)
		(instances
			(project "jetson-orin-baseboard"
				(path ""
					(reference "R87")
					(unit 1)
				)
			)
		)
	)
	(symbol
		(lib_name "C_100n_0402_4")
		(lib_id "antmicroCapacitors0402:C_100n_0402")
		(at 25.4 194.31 90)
		(mirror x)
		(unit 1)
		(exclude_from_sim no)
		(in_bom yes)
		(on_board yes)
		(dnp no)
		(fields_autoplaced yes)
		(property "Reference" "C27"
			(at 27.94 195.5863 90)
			(effects
				(font
					(size 1.27 1.27)
				)
				(justify right)
			)
		)
		(property "Value" "C_100n_0402"
			(at 35.56 214.63 0)
			(effects
				(font
					(size 1.27 1.27)
					(thickness 0.15)
				)
				(justify left bottom)
				(hide yes)
			)
		)
		(property "Footprint" "antmicro-footprints:C_0402_1005Metric"
			(at 38.1 214.63 0)
			(effects
				(font
					(size 1.27 1.27)
					(thickness 0.15)
				)
				(justify left bottom)
				(hide yes)
			)
		)
		(property "Datasheet" "https://www.murata.com/products/productdetail?partno=GRM155R61H104KE14%23"
			(at 40.64 214.63 0)
			(effects
				(font
					(size 1.27 1.27)
					(thickness 0.15)
				)
				(justify left bottom)
				(hide yes)
			)
		)
		(property "Description" ""
			(at 25.4 194.31 0)
			(effects
				(font
					(size 1.27 1.27)
				)
				(hide yes)
			)
		)
		(property "Manufacturer" "Murata"
			(at 45.72 214.63 0)
			(effects
				(font
					(size 1.27 1.27)
					(thickness 0.15)
				)
				(justify left bottom)
				(hide yes)
			)
		)
		(property "MPN" "GRM155R61H104KE14D"
			(at 43.18 214.63 0)
			(effects
				(font
					(size 1.27 1.27)
					(thickness 0.15)
				)
				(justify left bottom)
				(hide yes)
			)
		)
		(property "Val" "100n"
			(at 27.94 198.1263 90)
			(effects
				(font
					(size 1.27 1.27)
					(thickness 0.15)
				)
				(justify right)
			)
		)
		(property "License" "Apache-2.0"
			(at 48.26 214.63 0)
			(effects
				(font
					(size 1.27 1.27)
					(thickness 0.15)
				)
				(justify left bottom)
				(hide yes)
			)
		)
		(property "Author" "Antmicro"
			(at 50.8 214.63 0)
			(effects
				(font
					(size 1.27 1.27)
					(thickness 0.15)
				)
				(justify left bottom)
				(hide yes)
			)
		)
		(property "Voltage" "50V"
			(at 53.34 214.63 0)
			(effects
				(font
					(size 1.27 1.27)
				)
				(justify left bottom)
				(hide yes)
			)
		)
		(property "Dielectric" "X5R"
			(at 55.88 214.63 0)
			(effects
				(font
					(size 1.27 1.27)
				)
				(justify left bottom)
				(hide yes)
			)
		)
		(pin "1"
		)
		(pin "2"
		)
		(instances
			(project "jetson-orin-baseboard"
				(path ""
					(reference "C27")
					(unit 1)
				)
			)
		)
	)
	(symbol
		(lib_name "GND_3")
		(lib_id "antmicropower:GND")
		(at 351.79 204.47 0)
		(mirror y)
		(unit 1)
		(exclude_from_sim no)
		(in_bom yes)
		(on_board yes)
		(dnp no)
		(property "Reference" "#PWR0133"
			(at 351.79 210.82 0)
			(effects
				(font
					(size 1.27 1.27)
				)
				(justify left bottom)
				(hide yes)
			)
		)
		(property "Value" "GND"
			(at 351.79 208.28 0)
			(effects
				(font
					(size 1.27 1.27)
					(thickness 0.15)
				)
			)
		)
		(property "Footprint" ""
			(at 342.9 212.09 0)
			(effects
				(font
					(size 1.27 1.27)
					(thickness 0.15)
				)
				(justify left bottom)
				(hide yes)
			)
		)
		(property "Datasheet" ""
			(at 342.9 217.17 0)
			(effects
				(font
					(size 1.27 1.27)
					(thickness 0.15)
				)
				(justify left bottom)
				(hide yes)
			)
		)
		(property "Description" ""
			(at 351.79 204.47 0)
			(effects
				(font
					(size 1.27 1.27)
				)
				(hide yes)
			)
		)
		(property "Author" "Antmicro"
			(at 342.9 212.09 0)
			(effects
				(font
					(size 1.27 1.27)
					(thickness 0.15)
				)
				(justify left bottom)
				(hide yes)
			)
		)
		(property "License" "Apache-2.0"
			(at 342.9 214.63 0)
			(effects
				(font
					(size 1.27 1.27)
					(thickness 0.15)
				)
				(justify left bottom)
				(hide yes)
			)
		)
		(pin "1"
		)
		(instances
			(project "jetson-orin-baseboard"
				(path ""
					(reference "#PWR0133")
					(unit 1)
				)
			)
		)
	)
	(symbol
		(lib_id "antmicroResistors0402:R_1k_0402")
		(at 262.89 152.4 0)
		(unit 1)
		(exclude_from_sim no)
		(in_bom yes)
		(on_board yes)
		(dnp no)
		(property "Reference" "R90"
			(at 268.605 151.765 0)
			(effects
				(font
					(size 1.27 1.27)
				)
				(justify left bottom)
			)
		)
		(property "Value" "R_1k_0402"
			(at 283.21 165.1 0)
			(effects
				(font
					(size 1.27 1.27)
					(thickness 0.15)
				)
				(justify left bottom)
				(hide yes)
			)
		)
		(property "Footprint" "antmicro-footprints:R_0402_1005Metric"
			(at 283.21 167.64 0)
			(effects
				(font
					(size 1.27 1.27)
					(thickness 0.15)
				)
				(justify left bottom)
				(hide yes)
			)
		)
		(property "Datasheet" "https://www.bourns.com/docs/product-datasheets/cr.pdf"
			(at 283.21 170.18 0)
			(effects
				(font
					(size 1.27 1.27)
					(thickness 0.15)
				)
				(justify left bottom)
				(hide yes)
			)
		)
		(property "Description" ""
			(at 262.89 152.4 0)
			(effects
				(font
					(size 1.27 1.27)
				)
				(hide yes)
			)
		)
		(property "Manufacturer" "Bourns"
			(at 283.21 175.26 0)
			(effects
				(font
					(size 1.27 1.27)
					(thickness 0.15)
				)
				(justify left bottom)
				(hide yes)
			)
		)
		(property "MPN" "CR0402-FX-1001GLF"
			(at 283.21 172.72 0)
			(effects
				(font
					(size 1.27 1.27)
					(thickness 0.15)
				)
				(justify left bottom)
				(hide yes)
			)
		)
		(property "Val" "1k"
			(at 260.35 151.765 0)
			(effects
				(font
					(size 1.27 1.27)
					(thickness 0.15)
				)
				(justify left bottom)
			)
		)
		(property "License" "Apache-2.0"
			(at 283.21 177.8 0)
			(effects
				(font
					(size 1.27 1.27)
					(thickness 0.15)
				)
				(justify left bottom)
				(hide yes)
			)
		)
		(property "Author" "Antmicro"
			(at 283.21 180.34 0)
			(effects
				(font
					(size 1.27 1.27)
					(thickness 0.15)
				)
				(justify left bottom)
				(hide yes)
			)
		)
		(property "Tolerance" "1%"
			(at 283.21 162.56 0)
			(effects
				(font
					(size 1.27 1.27)
				)
				(justify left bottom)
				(hide yes)
			)
		)
		(pin "1"
		)
		(pin "2"
		)
		(instances
			(project "jetson-orin-baseboard"
				(path ""
					(reference "R90")
					(unit 1)
				)
			)
		)
	)
	(symbol
		(lib_id "antmicropower:+5V")
		(at 262.89 33.02 0)
		(unit 1)
		(exclude_from_sim no)
		(in_bom yes)
		(on_board yes)
		(dnp no)
		(property "Reference" "#PWR082"
			(at 262.89 36.83 0)
			(effects
				(font
					(size 1.27 1.27)
				)
				(justify left bottom)
				(hide yes)
			)
		)
		(property "Value" "+5V"
			(at 260.985 29.845 0)
			(effects
				(font
					(size 1.27 1.27)
					(thickness 0.15)
				)
				(justify left bottom)
			)
		)
		(property "Footprint" ""
			(at 278.13 40.64 0)
			(effects
				(font
					(size 1.27 1.27)
					(thickness 0.15)
				)
				(justify left bottom)
				(hide yes)
			)
		)
		(property "Datasheet" ""
			(at 278.13 43.18 0)
			(effects
				(font
					(size 1.27 1.27)
					(thickness 0.15)
				)
				(justify left bottom)
				(hide yes)
			)
		)
		(property "Description" ""
			(at 262.89 33.02 0)
			(effects
				(font
					(size 1.27 1.27)
				)
				(hide yes)
			)
		)
		(property "Author" "Antmicro"
			(at 278.13 40.64 0)
			(effects
				(font
					(size 1.27 1.27)
					(thickness 0.15)
				)
				(justify left bottom)
				(hide yes)
			)
		)
		(property "License" "Apache-2.0"
			(at 278.13 43.18 0)
			(effects
				(font
					(size 1.27 1.27)
					(thickness 0.15)
				)
				(justify left bottom)
				(hide yes)
			)
		)
		(pin "1"
		)
		(instances
			(project "jetson-orin-baseboard"
				(path ""
					(reference "#PWR082")
					(unit 1)
				)
			)
		)
	)
	(symbol
		(lib_id "antmicroTVSDiodes:TPD4E05U06QDQARQ1")
		(at 299.72 135.89 270)
		(unit 1)
		(exclude_from_sim no)
		(in_bom yes)
		(on_board yes)
		(dnp no)
		(fields_autoplaced yes)
		(property "Reference" "U13"
			(at 295.275 147.32 90)
			(effects
				(font
					(size 1.27 1.27)
				)
			)
		)
		(property "Value" "TPD4E05U06QDQARQ1"
			(at 289.56 160.02 0)
			(effects
				(font
					(size 1.27 1.27)
					(thickness 0.15)
				)
				(justify left bottom)
				(hide yes)
			)
		)
		(property "Footprint" "antmicro-footprints:USON-10_2.5x1mm_P0.5mm"
			(at 294.64 160.02 0)
			(effects
				(font
					(size 1.27 1.27)
					(thickness 0.15)
				)
				(justify left bottom)
				(hide yes)
			)
		)
		(property "Datasheet" "https://www.ti.com/lit/ds/symlink/tpd4e05u06-q1.pdf?HQS=dis-mous-null-mousermode-dsf-pf-null-wwe&ts=1663591265741&ref_url=https%253A%252F%252Fwww.mouser.com%252F"
			(at 292.1 160.02 0)
			(effects
				(font
					(size 1.27 1.27)
					(thickness 0.15)
				)
				(justify left bottom)
				(hide yes)
			)
		)
		(property "Description" ""
			(at 299.72 135.89 0)
			(effects
				(font
					(size 1.27 1.27)
				)
				(hide yes)
			)
		)
		(property "Manufacturer" "Texas Instruments"
			(at 287.02 160.02 0)
			(effects
				(font
					(size 1.27 1.27)
					(thickness 0.15)
				)
				(justify left bottom)
				(hide yes)
			)
		)
		(property "MPN" "TPD4E05U06QDQARQ1"
			(at 295.275 149.86 90)
			(effects
				(font
					(size 1.27 1.27)
					(thickness 0.15)
				)
			)
		)
		(property "Author" "Antmicro"
			(at 284.48 160.02 0)
			(effects
				(font
					(size 1.27 1.27)
					(thickness 0.15)
				)
				(justify left bottom)
				(hide yes)
			)
		)
		(property "License" "Apache-2.0"
			(at 281.94 160.02 0)
			(effects
				(font
					(size 1.27 1.27)
					(thickness 0.15)
				)
				(justify left bottom)
				(hide yes)
			)
		)
		(pin "1"
		)
		(pin "10"
		)
		(pin "2"
		)
		(pin "3"
		)
		(pin "4"
		)
		(pin "5"
		)
		(pin "6"
		)
		(pin "7"
		)
		(pin "8"
		)
		(pin "9"
		)
		(instances
			(project "jetson-orin-baseboard"
				(path ""
					(reference "U13")
					(unit 1)
				)
			)
		)
	)
	(symbol
		(lib_name "GND_3")
		(lib_id "antmicropower:GND")
		(at 273.05 71.12 0)
		(mirror y)
		(unit 1)
		(exclude_from_sim no)
		(in_bom yes)
		(on_board yes)
		(dnp no)
		(property "Reference" "#PWR084"
			(at 273.05 77.47 0)
			(effects
				(font
					(size 1.27 1.27)
				)
				(justify left bottom)
				(hide yes)
			)
		)
		(property "Value" "GND"
			(at 273.05 74.93 0)
			(effects
				(font
					(size 1.27 1.27)
					(thickness 0.15)
				)
			)
		)
		(property "Footprint" ""
			(at 264.16 78.74 0)
			(effects
				(font
					(size 1.27 1.27)
					(thickness 0.15)
				)
				(justify left bottom)
				(hide yes)
			)
		)
		(property "Datasheet" ""
			(at 264.16 83.82 0)
			(effects
				(font
					(size 1.27 1.27)
					(thickness 0.15)
				)
				(justify left bottom)
				(hide yes)
			)
		)
		(property "Description" ""
			(at 273.05 71.12 0)
			(effects
				(font
					(size 1.27 1.27)
				)
				(hide yes)
			)
		)
		(property "Author" "Antmicro"
			(at 264.16 78.74 0)
			(effects
				(font
					(size 1.27 1.27)
					(thickness 0.15)
				)
				(justify left bottom)
				(hide yes)
			)
		)
		(property "License" "Apache-2.0"
			(at 264.16 81.28 0)
			(effects
				(font
					(size 1.27 1.27)
					(thickness 0.15)
				)
				(justify left bottom)
				(hide yes)
			)
		)
		(pin "1"
		)
		(instances
			(project "jetson-orin-baseboard"
				(path ""
					(reference "#PWR084")
					(unit 1)
				)
			)
		)
	)
	(symbol
		(lib_name "GND_3")
		(lib_id "antmicropower:GND")
		(at 15.24 200.66 0)
		(mirror y)
		(unit 1)
		(exclude_from_sim no)
		(in_bom yes)
		(on_board yes)
		(dnp no)
		(property "Reference" "#PWR023"
			(at 15.24 207.01 0)
			(effects
				(font
					(size 1.27 1.27)
				)
				(justify left bottom)
				(hide yes)
			)
		)
		(property "Value" "GND"
			(at 15.24 204.47 0)
			(effects
				(font
					(size 1.27 1.27)
					(thickness 0.15)
				)
			)
		)
		(property "Footprint" ""
			(at 6.35 208.28 0)
			(effects
				(font
					(size 1.27 1.27)
					(thickness 0.15)
				)
				(justify left bottom)
				(hide yes)
			)
		)
		(property "Datasheet" ""
			(at 6.35 213.36 0)
			(effects
				(font
					(size 1.27 1.27)
					(thickness 0.15)
				)
				(justify left bottom)
				(hide yes)
			)
		)
		(property "Description" ""
			(at 15.24 200.66 0)
			(effects
				(font
					(size 1.27 1.27)
				)
				(hide yes)
			)
		)
		(property "Author" "Antmicro"
			(at 6.35 208.28 0)
			(effects
				(font
					(size 1.27 1.27)
					(thickness 0.15)
				)
				(justify left bottom)
				(hide yes)
			)
		)
		(property "License" "Apache-2.0"
			(at 6.35 210.82 0)
			(effects
				(font
					(size 1.27 1.27)
					(thickness 0.15)
				)
				(justify left bottom)
				(hide yes)
			)
		)
		(pin "1"
		)
		(instances
			(project "jetson-orin-baseboard"
				(path ""
					(reference "#PWR023")
					(unit 1)
				)
			)
		)
	)
	(symbol
		(lib_id "antmicroResistors0402:R_2k2_0402")
		(at 316.23 57.15 90)
		(unit 1)
		(exclude_from_sim no)
		(in_bom yes)
		(on_board yes)
		(dnp no)
		(property "Reference" "R104"
			(at 317.5 53.34 90)
			(effects
				(font
					(size 1.27 1.27)
				)
				(justify right)
			)
		)
		(property "Value" "R_2k2_0402"
			(at 328.93 36.83 0)
			(effects
				(font
					(size 1.27 1.27)
					(thickness 0.15)
				)
				(justify left bottom)
				(hide yes)
			)
		)
		(property "Footprint" "antmicro-footprints:R_0402_1005Metric"
			(at 331.47 36.83 0)
			(effects
				(font
					(size 1.27 1.27)
					(thickness 0.15)
				)
				(justify left bottom)
				(hide yes)
			)
		)
		(property "Datasheet" "https://www.bourns.com/docs/product-datasheets/cr.pdf"
			(at 334.01 36.83 0)
			(effects
				(font
					(size 1.27 1.27)
					(thickness 0.15)
				)
				(justify left bottom)
				(hide yes)
			)
		)
		(property "Description" ""
			(at 316.23 57.15 0)
			(effects
				(font
					(size 1.27 1.27)
				)
				(hide yes)
			)
		)
		(property "Manufacturer" "Bourns"
			(at 339.09 36.83 0)
			(effects
				(font
					(size 1.27 1.27)
					(thickness 0.15)
				)
				(justify left bottom)
				(hide yes)
			)
		)
		(property "MPN" "CR0402-FX-2201GLF"
			(at 336.55 36.83 0)
			(effects
				(font
					(size 1.27 1.27)
					(thickness 0.15)
				)
				(justify left bottom)
				(hide yes)
			)
		)
		(property "Val" "2k2"
			(at 317.5 55.88 90)
			(effects
				(font
					(size 1.27 1.27)
					(thickness 0.15)
				)
				(justify right)
			)
		)
		(property "License" "Apache-2.0"
			(at 341.63 36.83 0)
			(effects
				(font
					(size 1.27 1.27)
					(thickness 0.15)
				)
				(justify left bottom)
				(hide yes)
			)
		)
		(property "Author" "Antmicro"
			(at 344.17 36.83 0)
			(effects
				(font
					(size 1.27 1.27)
					(thickness 0.15)
				)
				(justify left bottom)
				(hide yes)
			)
		)
		(property "Tolerance" "1%"
			(at 326.39 36.83 0)
			(effects
				(font
					(size 1.27 1.27)
				)
				(justify left bottom)
				(hide yes)
			)
		)
		(pin "1"
		)
		(pin "2"
		)
		(instances
			(project "jetson-orin-baseboard"
				(path ""
					(reference "R104")
					(unit 1)
				)
			)
		)
	)
	(symbol
		(lib_name "GND_3")
		(lib_id "antmicropower:GND")
		(at 45.72 227.33 0)
		(mirror y)
		(unit 1)
		(exclude_from_sim no)
		(in_bom yes)
		(on_board yes)
		(dnp no)
		(property "Reference" "#PWR056"
			(at 45.72 233.68 0)
			(effects
				(font
					(size 1.27 1.27)
				)
				(justify left bottom)
				(hide yes)
			)
		)
		(property "Value" "GND"
			(at 45.72 231.14 0)
			(effects
				(font
					(size 1.27 1.27)
					(thickness 0.15)
				)
			)
		)
		(property "Footprint" ""
			(at 36.83 234.95 0)
			(effects
				(font
					(size 1.27 1.27)
					(thickness 0.15)
				)
				(justify left bottom)
				(hide yes)
			)
		)
		(property "Datasheet" ""
			(at 36.83 240.03 0)
			(effects
				(font
					(size 1.27 1.27)
					(thickness 0.15)
				)
				(justify left bottom)
				(hide yes)
			)
		)
		(property "Description" ""
			(at 45.72 227.33 0)
			(effects
				(font
					(size 1.27 1.27)
				)
				(hide yes)
			)
		)
		(property "Author" "Antmicro"
			(at 36.83 234.95 0)
			(effects
				(font
					(size 1.27 1.27)
					(thickness 0.15)
				)
				(justify left bottom)
				(hide yes)
			)
		)
		(property "License" "Apache-2.0"
			(at 36.83 237.49 0)
			(effects
				(font
					(size 1.27 1.27)
					(thickness 0.15)
				)
				(justify left bottom)
				(hide yes)
			)
		)
		(pin "1"
		)
		(instances
			(project "jetson-orin-baseboard"
				(path ""
					(reference "#PWR056")
					(unit 1)
				)
			)
		)
	)
	(symbol
		(lib_id "antmicroCapacitors0402:C_47p_0402")
		(at 346.71 224.79 90)
		(mirror x)
		(unit 1)
		(exclude_from_sim no)
		(in_bom yes)
		(on_board yes)
		(dnp no)
		(fields_autoplaced yes)
		(property "Reference" "C146"
			(at 349.25 226.0663 90)
			(effects
				(font
					(size 1.27 1.27)
					(thickness 0.15)
				)
				(justify right)
			)
		)
		(property "Value" "C_47p_0402"
			(at 356.87 245.11 0)
			(effects
				(font
					(size 1.27 1.27)
					(thickness 0.15)
				)
				(justify left bottom)
				(hide yes)
			)
		)
		(property "Footprint" "antmicro-footprints:C_0402_1005Metric"
			(at 359.41 245.11 0)
			(effects
				(font
					(size 1.27 1.27)
					(thickness 0.15)
				)
				(justify left bottom)
				(hide yes)
			)
		)
		(property "Datasheet" "https://www.kemet.com/en/us/capacitors/product/C0402C470J5GACTU.html"
			(at 361.95 245.11 0)
			(effects
				(font
					(size 1.27 1.27)
					(thickness 0.15)
				)
				(justify left bottom)
				(hide yes)
			)
		)
		(property "Description" ""
			(at 346.71 224.79 0)
			(effects
				(font
					(size 1.27 1.27)
				)
				(hide yes)
			)
		)
		(property "MPN" "C0402C470J5GACTU"
			(at 364.49 245.11 0)
			(effects
				(font
					(size 1.27 1.27)
					(thickness 0.15)
				)
				(justify left bottom)
				(hide yes)
			)
		)
		(property "Manufacturer" "KEMET"
			(at 367.03 245.11 0)
			(effects
				(font
					(size 1.27 1.27)
					(thickness 0.15)
				)
				(justify left bottom)
				(hide yes)
			)
		)
		(property "License" "Apache-2.0"
			(at 369.57 245.11 0)
			(effects
				(font
					(size 1.27 1.27)
					(thickness 0.15)
				)
				(justify left bottom)
				(hide yes)
			)
		)
		(property "Author" "Antmicro"
			(at 372.11 245.11 0)
			(effects
				(font
					(size 1.27 1.27)
					(thickness 0.15)
				)
				(justify left bottom)
				(hide yes)
			)
		)
		(property "Val" "47p"
			(at 349.25 228.6063 90)
			(effects
				(font
					(size 1.27 1.27)
					(thickness 0.15)
				)
				(justify right)
			)
		)
		(property "Voltage" ""
			(at 374.65 245.11 0)
			(effects
				(font
					(size 1.27 1.27)
				)
				(justify left bottom)
				(hide yes)
			)
		)
		(property "Dielectric" "C0G"
			(at 377.19 245.11 0)
			(effects
				(font
					(size 1.27 1.27)
				)
				(justify left bottom)
				(hide yes)
			)
		)
		(pin "2"
		)
		(pin "1"
		)
		(instances
			(project "jetson-orin-baseboard"
				(path ""
					(reference "C146")
					(unit 1)
				)
			)
		)
	)
	(symbol
		(lib_name "GND_3")
		(lib_id "antmicropower:GND")
		(at 299.72 243.84 0)
		(mirror y)
		(unit 1)
		(exclude_from_sim no)
		(in_bom yes)
		(on_board yes)
		(dnp no)
		(property "Reference" "#PWR0194"
			(at 299.72 250.19 0)
			(effects
				(font
					(size 1.27 1.27)
				)
				(justify left bottom)
				(hide yes)
			)
		)
		(property "Value" "GND"
			(at 299.72 247.65 0)
			(effects
				(font
					(size 1.27 1.27)
					(thickness 0.15)
				)
			)
		)
		(property "Footprint" ""
			(at 290.83 251.46 0)
			(effects
				(font
					(size 1.27 1.27)
					(thickness 0.15)
				)
				(justify left bottom)
				(hide yes)
			)
		)
		(property "Datasheet" ""
			(at 290.83 256.54 0)
			(effects
				(font
					(size 1.27 1.27)
					(thickness 0.15)
				)
				(justify left bottom)
				(hide yes)
			)
		)
		(property "Description" ""
			(at 299.72 243.84 0)
			(effects
				(font
					(size 1.27 1.27)
				)
				(hide yes)
			)
		)
		(property "Author" "Antmicro"
			(at 290.83 251.46 0)
			(effects
				(font
					(size 1.27 1.27)
					(thickness 0.15)
				)
				(justify left bottom)
				(hide yes)
			)
		)
		(property "License" "Apache-2.0"
			(at 290.83 254 0)
			(effects
				(font
					(size 1.27 1.27)
					(thickness 0.15)
				)
				(justify left bottom)
				(hide yes)
			)
		)
		(pin "1"
		)
		(instances
			(project "jetson-orin-baseboard"
				(path ""
					(reference "#PWR0194")
					(unit 1)
				)
			)
		)
	)
	(symbol
		(lib_name "C_100n_0402_5")
		(lib_id "antmicroCapacitors0402:C_100n_0402")
		(at 41.91 220.98 270)
		(unit 1)
		(exclude_from_sim no)
		(in_bom yes)
		(on_board yes)
		(dnp no)
		(property "Reference" "C31"
			(at 40.005 222.25 90)
			(effects
				(font
					(size 1.27 1.27)
				)
				(justify right)
			)
		)
		(property "Value" "C_100n_0402"
			(at 31.75 241.3 0)
			(effects
				(font
					(size 1.27 1.27)
					(thickness 0.15)
				)
				(justify left bottom)
				(hide yes)
			)
		)
		(property "Footprint" "antmicro-footprints:C_0402_1005Metric"
			(at 29.21 241.3 0)
			(effects
				(font
					(size 1.27 1.27)
					(thickness 0.15)
				)
				(justify left bottom)
				(hide yes)
			)
		)
		(property "Datasheet" "https://www.murata.com/products/productdetail?partno=GRM155R61H104KE14%23"
			(at 26.67 241.3 0)
			(effects
				(font
					(size 1.27 1.27)
					(thickness 0.15)
				)
				(justify left bottom)
				(hide yes)
			)
		)
		(property "Description" ""
			(at 41.91 220.98 0)
			(effects
				(font
					(size 1.27 1.27)
				)
				(hide yes)
			)
		)
		(property "Manufacturer" "Murata"
			(at 21.59 241.3 0)
			(effects
				(font
					(size 1.27 1.27)
					(thickness 0.15)
				)
				(justify left bottom)
				(hide yes)
			)
		)
		(property "MPN" "GRM155R61H104KE14D"
			(at 24.13 241.3 0)
			(effects
				(font
					(size 1.27 1.27)
					(thickness 0.15)
				)
				(justify left bottom)
				(hide yes)
			)
		)
		(property "Val" "100n"
			(at 40.005 224.79 90)
			(effects
				(font
					(size 1.27 1.27)
					(thickness 0.15)
				)
				(justify right)
			)
		)
		(property "License" "Apache-2.0"
			(at 19.05 241.3 0)
			(effects
				(font
					(size 1.27 1.27)
					(thickness 0.15)
				)
				(justify left bottom)
				(hide yes)
			)
		)
		(property "Author" "Antmicro"
			(at 16.51 241.3 0)
			(effects
				(font
					(size 1.27 1.27)
					(thickness 0.15)
				)
				(justify left bottom)
				(hide yes)
			)
		)
		(property "Voltage" "50V"
			(at 13.97 241.3 0)
			(effects
				(font
					(size 1.27 1.27)
				)
				(justify left bottom)
				(hide yes)
			)
		)
		(property "Dielectric" "X5R"
			(at 11.43 241.3 0)
			(effects
				(font
					(size 1.27 1.27)
				)
				(justify left bottom)
				(hide yes)
			)
		)
		(pin "1"
		)
		(pin "2"
		)
		(instances
			(project "jetson-orin-baseboard"
				(path ""
					(reference "C31")
					(unit 1)
				)
			)
		)
	)
	(symbol
		(lib_name "GND_3")
		(lib_id "antmicropower:GND")
		(at 237.49 173.99 0)
		(mirror y)
		(unit 1)
		(exclude_from_sim no)
		(in_bom yes)
		(on_board yes)
		(dnp no)
		(property "Reference" "#PWR080"
			(at 237.49 180.34 0)
			(effects
				(font
					(size 1.27 1.27)
				)
				(justify left bottom)
				(hide yes)
			)
		)
		(property "Value" "GND"
			(at 237.49 177.8 0)
			(effects
				(font
					(size 1.27 1.27)
					(thickness 0.15)
				)
			)
		)
		(property "Footprint" ""
			(at 228.6 181.61 0)
			(effects
				(font
					(size 1.27 1.27)
					(thickness 0.15)
				)
				(justify left bottom)
				(hide yes)
			)
		)
		(property "Datasheet" ""
			(at 228.6 186.69 0)
			(effects
				(font
					(size 1.27 1.27)
					(thickness 0.15)
				)
				(justify left bottom)
				(hide yes)
			)
		)
		(property "Description" ""
			(at 237.49 173.99 0)
			(effects
				(font
					(size 1.27 1.27)
				)
				(hide yes)
			)
		)
		(property "Author" "Antmicro"
			(at 228.6 181.61 0)
			(effects
				(font
					(size 1.27 1.27)
					(thickness 0.15)
				)
				(justify left bottom)
				(hide yes)
			)
		)
		(property "License" "Apache-2.0"
			(at 228.6 184.15 0)
			(effects
				(font
					(size 1.27 1.27)
					(thickness 0.15)
				)
				(justify left bottom)
				(hide yes)
			)
		)
		(pin "1"
		)
		(instances
			(project "jetson-orin-baseboard"
				(path ""
					(reference "#PWR080")
					(unit 1)
				)
			)
		)
	)
	(symbol
		(lib_id "antmicroResistors0402:R_1k_0402")
		(at 262.89 170.18 0)
		(unit 1)
		(exclude_from_sim no)
		(in_bom no)
		(on_board yes)
		(dnp yes)
		(property "Reference" "R97"
			(at 268.605 169.545 0)
			(effects
				(font
					(size 1.27 1.27)
				)
				(justify left bottom)
			)
		)
		(property "Value" "R_1k_0402"
			(at 283.21 182.88 0)
			(effects
				(font
					(size 1.27 1.27)
					(thickness 0.15)
				)
				(justify left bottom)
				(hide yes)
			)
		)
		(property "Footprint" "antmicro-footprints:R_0402_1005Metric"
			(at 283.21 185.42 0)
			(effects
				(font
					(size 1.27 1.27)
					(thickness 0.15)
				)
				(justify left bottom)
				(hide yes)
			)
		)
		(property "Datasheet" "https://www.bourns.com/docs/product-datasheets/cr.pdf"
			(at 283.21 187.96 0)
			(effects
				(font
					(size 1.27 1.27)
					(thickness 0.15)
				)
				(justify left bottom)
				(hide yes)
			)
		)
		(property "Description" ""
			(at 262.89 170.18 0)
			(effects
				(font
					(size 1.27 1.27)
				)
				(hide yes)
			)
		)
		(property "Manufacturer" "Bourns"
			(at 283.21 193.04 0)
			(effects
				(font
					(size 1.27 1.27)
					(thickness 0.15)
				)
				(justify left bottom)
				(hide yes)
			)
		)
		(property "MPN" "CR0402-FX-1001GLF"
			(at 283.21 190.5 0)
			(effects
				(font
					(size 1.27 1.27)
					(thickness 0.15)
				)
				(justify left bottom)
				(hide yes)
			)
		)
		(property "Val" "1k"
			(at 260.35 169.545 0)
			(effects
				(font
					(size 1.27 1.27)
					(thickness 0.15)
				)
				(justify left bottom)
			)
		)
		(property "License" "Apache-2.0"
			(at 283.21 195.58 0)
			(effects
				(font
					(size 1.27 1.27)
					(thickness 0.15)
				)
				(justify left bottom)
				(hide yes)
			)
		)
		(property "Author" "Antmicro"
			(at 283.21 198.12 0)
			(effects
				(font
					(size 1.27 1.27)
					(thickness 0.15)
				)
				(justify left bottom)
				(hide yes)
			)
		)
		(property "Tolerance" "1%"
			(at 283.21 180.34 0)
			(effects
				(font
					(size 1.27 1.27)
				)
				(justify left bottom)
				(hide yes)
			)
		)
		(pin "1"
		)
		(pin "2"
		)
		(instances
			(project "jetson-orin-baseboard"
				(path ""
					(reference "R97")
					(unit 1)
				)
			)
		)
	)
	(symbol
		(lib_name "R_0R_0402_9")
		(lib_id "antmicroResistors0402:R_0R_0402")
		(at 78.74 209.55 0)
		(mirror y)
		(unit 1)
		(exclude_from_sim no)
		(in_bom no)
		(on_board yes)
		(dnp yes)
		(property "Reference" "R59"
			(at 78.74 208.915 0)
			(effects
				(font
					(size 1.27 1.27)
				)
				(justify right bottom)
			)
		)
		(property "Value" "R_0R_0402"
			(at 58.42 222.25 0)
			(effects
				(font
					(size 1.27 1.27)
					(thickness 0.15)
				)
				(justify left bottom)
				(hide yes)
			)
		)
		(property "Footprint" "antmicro-footprints:R_0402_1005Metric"
			(at 58.42 224.79 0)
			(effects
				(font
					(size 1.27 1.27)
					(thickness 0.15)
				)
				(justify left bottom)
				(hide yes)
			)
		)
		(property "Datasheet" "https://industrial.panasonic.com/cdbs/www-data/pdf/RDA0000/AOA0000C301.pdf"
			(at 58.42 227.33 0)
			(effects
				(font
					(size 1.27 1.27)
					(thickness 0.15)
				)
				(justify left bottom)
				(hide yes)
			)
		)
		(property "Description" ""
			(at 78.74 209.55 0)
			(effects
				(font
					(size 1.27 1.27)
				)
				(hide yes)
			)
		)
		(property "Manufacturer" "Panasonic"
			(at 58.42 232.41 0)
			(effects
				(font
					(size 1.27 1.27)
					(thickness 0.15)
				)
				(justify left bottom)
				(hide yes)
			)
		)
		(property "MPN" "ERJ2GE0R00X"
			(at 58.42 229.87 0)
			(effects
				(font
					(size 1.27 1.27)
					(thickness 0.15)
				)
				(justify left bottom)
				(hide yes)
			)
		)
		(property "Val" "0R"
			(at 71.12 208.915 0)
			(effects
				(font
					(size 1.27 1.27)
					(thickness 0.15)
				)
				(justify right bottom)
			)
		)
		(property "License" "Apache-2.0"
			(at 58.42 234.95 0)
			(effects
				(font
					(size 1.27 1.27)
					(thickness 0.15)
				)
				(justify left bottom)
				(hide yes)
			)
		)
		(property "Author" "Antmicro"
			(at 58.42 237.49 0)
			(effects
				(font
					(size 1.27 1.27)
					(thickness 0.15)
				)
				(justify left bottom)
				(hide yes)
			)
		)
		(property "Tolerance" "~"
			(at 58.42 219.71 0)
			(effects
				(font
					(size 1.27 1.27)
				)
				(justify left bottom)
				(hide yes)
			)
		)
		(property "Current" "1A"
			(at 58.42 240.03 0)
			(effects
				(font
					(size 1.27 1.27)
					(thickness 0.15)
				)
				(justify left bottom)
				(hide yes)
			)
		)
		(pin "1"
		)
		(pin "2"
		)
		(instances
			(project "jetson-orin-baseboard"
				(path ""
					(reference "R59")
					(unit 1)
				)
			)
		)
	)
	(symbol
		(lib_name "R_0R_0402_8")
		(lib_id "antmicroResistors0402:R_0R_0402")
		(at 78.74 204.47 0)
		(mirror y)
		(unit 1)
		(exclude_from_sim no)
		(in_bom yes)
		(on_board yes)
		(dnp no)
		(property "Reference" "R57"
			(at 78.74 203.835 0)
			(effects
				(font
					(size 1.27 1.27)
				)
				(justify right bottom)
			)
		)
		(property "Value" "R_0R_0402"
			(at 58.42 217.17 0)
			(effects
				(font
					(size 1.27 1.27)
					(thickness 0.15)
				)
				(justify left bottom)
				(hide yes)
			)
		)
		(property "Footprint" "antmicro-footprints:R_0402_1005Metric"
			(at 58.42 219.71 0)
			(effects
				(font
					(size 1.27 1.27)
					(thickness 0.15)
				)
				(justify left bottom)
				(hide yes)
			)
		)
		(property "Datasheet" "https://industrial.panasonic.com/cdbs/www-data/pdf/RDA0000/AOA0000C301.pdf"
			(at 58.42 222.25 0)
			(effects
				(font
					(size 1.27 1.27)
					(thickness 0.15)
				)
				(justify left bottom)
				(hide yes)
			)
		)
		(property "Description" ""
			(at 78.74 204.47 0)
			(effects
				(font
					(size 1.27 1.27)
				)
				(hide yes)
			)
		)
		(property "Manufacturer" "Panasonic"
			(at 58.42 227.33 0)
			(effects
				(font
					(size 1.27 1.27)
					(thickness 0.15)
				)
				(justify left bottom)
				(hide yes)
			)
		)
		(property "MPN" "ERJ2GE0R00X"
			(at 58.42 224.79 0)
			(effects
				(font
					(size 1.27 1.27)
					(thickness 0.15)
				)
				(justify left bottom)
				(hide yes)
			)
		)
		(property "Val" "0R"
			(at 71.12 203.835 0)
			(effects
				(font
					(size 1.27 1.27)
					(thickness 0.15)
				)
				(justify right bottom)
			)
		)
		(property "License" "Apache-2.0"
			(at 58.42 229.87 0)
			(effects
				(font
					(size 1.27 1.27)
					(thickness 0.15)
				)
				(justify left bottom)
				(hide yes)
			)
		)
		(property "Author" "Antmicro"
			(at 58.42 232.41 0)
			(effects
				(font
					(size 1.27 1.27)
					(thickness 0.15)
				)
				(justify left bottom)
				(hide yes)
			)
		)
		(property "Tolerance" "~"
			(at 58.42 214.63 0)
			(effects
				(font
					(size 1.27 1.27)
				)
				(justify left bottom)
				(hide yes)
			)
		)
		(property "Current" "1A"
			(at 58.42 234.95 0)
			(effects
				(font
					(size 1.27 1.27)
					(thickness 0.15)
				)
				(justify left bottom)
				(hide yes)
			)
		)
		(pin "1"
		)
		(pin "2"
		)
		(instances
			(project "jetson-orin-baseboard"
				(path ""
					(reference "R57")
					(unit 1)
				)
			)
		)
	)
	(symbol
		(lib_name "+5V_2")
		(lib_id "antmicropower:+5V")
		(at 173.99 199.39 0)
		(unit 1)
		(exclude_from_sim no)
		(in_bom yes)
		(on_board yes)
		(dnp no)
		(property "Reference" "#PWR072"
			(at 173.99 203.2 0)
			(effects
				(font
					(size 1.27 1.27)
				)
				(justify left bottom)
				(hide yes)
			)
		)
		(property "Value" "+5V"
			(at 171.45 195.58 0)
			(effects
				(font
					(size 1.27 1.27)
					(thickness 0.15)
				)
				(justify left)
			)
		)
		(property "Footprint" ""
			(at 189.23 207.01 0)
			(effects
				(font
					(size 1.27 1.27)
					(thickness 0.15)
				)
				(justify left bottom)
				(hide yes)
			)
		)
		(property "Datasheet" ""
			(at 189.23 209.55 0)
			(effects
				(font
					(size 1.27 1.27)
					(thickness 0.15)
				)
				(justify left bottom)
				(hide yes)
			)
		)
		(property "Description" ""
			(at 173.99 199.39 0)
			(effects
				(font
					(size 1.27 1.27)
				)
				(hide yes)
			)
		)
		(property "Author" "Antmicro"
			(at 189.23 207.01 0)
			(effects
				(font
					(size 1.27 1.27)
					(thickness 0.15)
				)
				(justify left bottom)
				(hide yes)
			)
		)
		(property "License" "Apache-2.0"
			(at 189.23 209.55 0)
			(effects
				(font
					(size 1.27 1.27)
					(thickness 0.15)
				)
				(justify left bottom)
				(hide yes)
			)
		)
		(pin "1"
		)
		(instances
			(project "jetson-orin-baseboard"
				(path ""
					(reference "#PWR072")
					(unit 1)
				)
			)
		)
	)
	(symbol
		(lib_name "R_4k7_0402_5")
		(lib_id "antmicroResistors0402:R_4k7_0402")
		(at 351.79 191.77 270)
		(unit 1)
		(exclude_from_sim no)
		(in_bom yes)
		(on_board yes)
		(dnp no)
		(fields_autoplaced yes)
		(property "Reference" "R105"
			(at 353.695 193.04 90)
			(effects
				(font
					(size 1.27 1.27)
				)
				(justify left)
			)
		)
		(property "Value" "R_4k7_0402"
			(at 339.09 212.09 0)
			(effects
				(font
					(size 1.27 1.27)
					(thickness 0.15)
				)
				(justify left bottom)
				(hide yes)
			)
		)
		(property "Footprint" "antmicro-footprints:R_0402_1005Metric"
			(at 336.55 212.09 0)
			(effects
				(font
					(size 1.27 1.27)
					(thickness 0.15)
				)
				(justify left bottom)
				(hide yes)
			)
		)
		(property "Datasheet" "https://www.bourns.com/docs/product-datasheets/cr.pdf"
			(at 334.01 212.09 0)
			(effects
				(font
					(size 1.27 1.27)
					(thickness 0.15)
				)
				(justify left bottom)
				(hide yes)
			)
		)
		(property "Description" ""
			(at 351.79 191.77 0)
			(effects
				(font
					(size 1.27 1.27)
				)
				(hide yes)
			)
		)
		(property "Manufacturer" "Bourns"
			(at 328.93 212.09 0)
			(effects
				(font
					(size 1.27 1.27)
					(thickness 0.15)
				)
				(justify left bottom)
				(hide yes)
			)
		)
		(property "MPN" "CR0402-FX-4701GLF"
			(at 331.47 212.09 0)
			(effects
				(font
					(size 1.27 1.27)
					(thickness 0.15)
				)
				(justify left bottom)
				(hide yes)
			)
		)
		(property "Val" "4k7"
			(at 353.695 195.58 90)
			(effects
				(font
					(size 1.27 1.27)
					(thickness 0.15)
				)
				(justify left)
			)
		)
		(property "License" "Apache-2.0"
			(at 326.39 212.09 0)
			(effects
				(font
					(size 1.27 1.27)
					(thickness 0.15)
				)
				(justify left bottom)
				(hide yes)
			)
		)
		(property "Author" "Antmicro"
			(at 323.85 212.09 0)
			(effects
				(font
					(size 1.27 1.27)
					(thickness 0.15)
				)
				(justify left bottom)
				(hide yes)
			)
		)
		(property "Tolerance" "1%"
			(at 341.63 212.09 0)
			(effects
				(font
					(size 1.27 1.27)
				)
				(justify left bottom)
				(hide yes)
			)
		)
		(pin "1"
		)
		(pin "2"
		)
		(instances
			(project "jetson-orin-baseboard"
				(path ""
					(reference "R105")
					(unit 1)
				)
			)
		)
	)
	(symbol
		(lib_name "GND_3")
		(lib_id "antmicropower:GND")
		(at 76.2 132.08 0)
		(mirror y)
		(unit 1)
		(exclude_from_sim no)
		(in_bom yes)
		(on_board yes)
		(dnp no)
		(property "Reference" "#PWR062"
			(at 76.2 138.43 0)
			(effects
				(font
					(size 1.27 1.27)
				)
				(justify left bottom)
				(hide yes)
			)
		)
		(property "Value" "GND"
			(at 76.2 135.89 0)
			(effects
				(font
					(size 1.27 1.27)
					(thickness 0.15)
				)
			)
		)
		(property "Footprint" ""
			(at 67.31 139.7 0)
			(effects
				(font
					(size 1.27 1.27)
					(thickness 0.15)
				)
				(justify left bottom)
				(hide yes)
			)
		)
		(property "Datasheet" ""
			(at 67.31 144.78 0)
			(effects
				(font
					(size 1.27 1.27)
					(thickness 0.15)
				)
				(justify left bottom)
				(hide yes)
			)
		)
		(property "Description" ""
			(at 76.2 132.08 0)
			(effects
				(font
					(size 1.27 1.27)
				)
				(hide yes)
			)
		)
		(property "Author" "Antmicro"
			(at 67.31 139.7 0)
			(effects
				(font
					(size 1.27 1.27)
					(thickness 0.15)
				)
				(justify left bottom)
				(hide yes)
			)
		)
		(property "License" "Apache-2.0"
			(at 67.31 142.24 0)
			(effects
				(font
					(size 1.27 1.27)
					(thickness 0.15)
				)
				(justify left bottom)
				(hide yes)
			)
		)
		(pin "1"
		)
		(instances
			(project "jetson-orin-baseboard"
				(path ""
					(reference "#PWR062")
					(unit 1)
				)
			)
		)
	)
	(symbol
		(lib_name "GND_3")
		(lib_id "antmicropower:GND")
		(at 39.37 262.89 0)
		(mirror y)
		(unit 1)
		(exclude_from_sim no)
		(in_bom yes)
		(on_board yes)
		(dnp no)
		(property "Reference" "#PWR0270"
			(at 39.37 269.24 0)
			(effects
				(font
					(size 1.27 1.27)
				)
				(justify left bottom)
				(hide yes)
			)
		)
		(property "Value" "GND"
			(at 39.37 266.7 0)
			(effects
				(font
					(size 1.27 1.27)
					(thickness 0.15)
				)
			)
		)
		(property "Footprint" ""
			(at 30.48 270.51 0)
			(effects
				(font
					(size 1.27 1.27)
					(thickness 0.15)
				)
				(justify left bottom)
				(hide yes)
			)
		)
		(property "Datasheet" ""
			(at 30.48 275.59 0)
			(effects
				(font
					(size 1.27 1.27)
					(thickness 0.15)
				)
				(justify left bottom)
				(hide yes)
			)
		)
		(property "Description" ""
			(at 39.37 262.89 0)
			(effects
				(font
					(size 1.27 1.27)
				)
				(hide yes)
			)
		)
		(property "Author" "Antmicro"
			(at 30.48 270.51 0)
			(effects
				(font
					(size 1.27 1.27)
					(thickness 0.15)
				)
				(justify left bottom)
				(hide yes)
			)
		)
		(property "License" "Apache-2.0"
			(at 30.48 273.05 0)
			(effects
				(font
					(size 1.27 1.27)
					(thickness 0.15)
				)
				(justify left bottom)
				(hide yes)
			)
		)
		(pin "1"
		)
		(instances
			(project "jetson-orin-baseboard"
				(path ""
					(reference "#PWR0270")
					(unit 1)
				)
			)
		)
	)
	(symbol
		(lib_name "R_10k_0402_4")
		(lib_id "antmicroResistors0402:R_10k_0402")
		(at 198.12 207.01 90)
		(unit 1)
		(exclude_from_sim no)
		(in_bom yes)
		(on_board yes)
		(dnp no)
		(property "Reference" "R74"
			(at 199.39 203.2 90)
			(effects
				(font
					(size 1.27 1.27)
				)
				(justify right)
			)
		)
		(property "Value" "R_10k_0402"
			(at 210.82 186.69 0)
			(effects
				(font
					(size 1.27 1.27)
					(thickness 0.15)
				)
				(justify left bottom)
				(hide yes)
			)
		)
		(property "Footprint" "antmicro-footprints:R_0402_1005Metric"
			(at 213.36 186.69 0)
			(effects
				(font
					(size 1.27 1.27)
					(thickness 0.15)
				)
				(justify left bottom)
				(hide yes)
			)
		)
		(property "Datasheet" "https://www.bourns.com/docs/product-datasheets/cr.pdf"
			(at 215.9 186.69 0)
			(effects
				(font
					(size 1.27 1.27)
					(thickness 0.15)
				)
				(justify left bottom)
				(hide yes)
			)
		)
		(property "Description" ""
			(at 198.12 207.01 0)
			(effects
				(font
					(size 1.27 1.27)
				)
				(hide yes)
			)
		)
		(property "Manufacturer" "Bourns"
			(at 220.98 186.69 0)
			(effects
				(font
					(size 1.27 1.27)
					(thickness 0.15)
				)
				(justify left bottom)
				(hide yes)
			)
		)
		(property "MPN" "CR0402-FX-1002GLF"
			(at 218.44 186.69 0)
			(effects
				(font
					(size 1.27 1.27)
					(thickness 0.15)
				)
				(justify left bottom)
				(hide yes)
			)
		)
		(property "Val" "10k"
			(at 199.39 205.74 90)
			(effects
				(font
					(size 1.27 1.27)
					(thickness 0.15)
				)
				(justify right)
			)
		)
		(property "License" "Apache-2.0"
			(at 223.52 186.69 0)
			(effects
				(font
					(size 1.27 1.27)
					(thickness 0.15)
				)
				(justify left bottom)
				(hide yes)
			)
		)
		(property "Author" "Antmicro"
			(at 226.06 186.69 0)
			(effects
				(font
					(size 1.27 1.27)
					(thickness 0.15)
				)
				(justify left bottom)
				(hide yes)
			)
		)
		(property "Tolerance" "1%"
			(at 208.28 186.69 0)
			(effects
				(font
					(size 1.27 1.27)
				)
				(justify left bottom)
				(hide yes)
			)
		)
		(pin "1"
		)
		(pin "2"
		)
		(instances
			(project "jetson-orin-baseboard"
				(path ""
					(reference "R74")
					(unit 1)
				)
			)
		)
	)
	(symbol
		(lib_name "GND_3")
		(lib_id "antmicropower:GND")
		(at 58.42 179.07 0)
		(mirror y)
		(unit 1)
		(exclude_from_sim no)
		(in_bom yes)
		(on_board yes)
		(dnp no)
		(property "Reference" "#PWR065"
			(at 58.42 185.42 0)
			(effects
				(font
					(size 1.27 1.27)
				)
				(justify left bottom)
				(hide yes)
			)
		)
		(property "Value" "GND"
			(at 58.42 182.88 0)
			(effects
				(font
					(size 1.27 1.27)
					(thickness 0.15)
				)
			)
		)
		(property "Footprint" ""
			(at 49.53 186.69 0)
			(effects
				(font
					(size 1.27 1.27)
					(thickness 0.15)
				)
				(justify left bottom)
				(hide yes)
			)
		)
		(property "Datasheet" ""
			(at 49.53 191.77 0)
			(effects
				(font
					(size 1.27 1.27)
					(thickness 0.15)
				)
				(justify left bottom)
				(hide yes)
			)
		)
		(property "Description" ""
			(at 58.42 179.07 0)
			(effects
				(font
					(size 1.27 1.27)
				)
				(hide yes)
			)
		)
		(property "Author" "Antmicro"
			(at 49.53 186.69 0)
			(effects
				(font
					(size 1.27 1.27)
					(thickness 0.15)
				)
				(justify left bottom)
				(hide yes)
			)
		)
		(property "License" "Apache-2.0"
			(at 49.53 189.23 0)
			(effects
				(font
					(size 1.27 1.27)
					(thickness 0.15)
				)
				(justify left bottom)
				(hide yes)
			)
		)
		(pin "1"
		)
		(instances
			(project "jetson-orin-baseboard"
				(path ""
					(reference "#PWR065")
					(unit 1)
				)
			)
		)
	)
	(symbol
		(lib_id "antmicroResistorNetworksArrays:R_4x0R_0201_array")
		(at 102.87 46.99 0)
		(mirror x)
		(unit 1)
		(exclude_from_sim no)
		(in_bom yes)
		(on_board yes)
		(dnp no)
		(fields_autoplaced yes)
		(property "Reference" "R33"
			(at 107.95 33.02 0)
			(effects
				(font
					(size 1.27 1.27)
				)
			)
		)
		(property "Value" "R_4x0R_0201_array"
			(at 129.54 39.37 0)
			(effects
				(font
					(size 1.27 1.27)
					(thickness 0.15)
				)
				(justify left bottom)
				(hide yes)
			)
		)
		(property "Footprint" "antmicro-footprints:R_Array_4x0201_Panasonic_EXB18V"
			(at 129.54 34.29 0)
			(effects
				(font
					(size 1.27 1.27)
					(thickness 0.15)
				)
				(justify left bottom)
				(hide yes)
			)
		)
		(property "Datasheet" "http://industrial.panasonic.com/cdbs/www-data/pdf/AOC0000/AOC0000C14.pdf"
			(at 129.54 31.75 0)
			(effects
				(font
					(size 1.27 1.27)
					(thickness 0.15)
				)
				(justify left bottom)
				(hide yes)
			)
		)
		(property "Description" ""
			(at 102.87 46.99 0)
			(effects
				(font
					(size 1.27 1.27)
				)
				(hide yes)
			)
		)
		(property "MPN" "EXB-18VR000X"
			(at 129.54 29.21 0)
			(effects
				(font
					(size 1.27 1.27)
					(thickness 0.15)
				)
				(justify left bottom)
				(hide yes)
			)
		)
		(property "Manufacturer" "Panasonic"
			(at 129.54 26.67 0)
			(effects
				(font
					(size 1.27 1.27)
					(thickness 0.15)
				)
				(justify left bottom)
				(hide yes)
			)
		)
		(property "Val" "4x0R_0201"
			(at 107.95 35.56 0)
			(effects
				(font
					(size 1.27 1.27)
					(thickness 0.15)
				)
			)
		)
		(property "Author" "Antmicro"
			(at 129.54 24.13 0)
			(effects
				(font
					(size 1.27 1.27)
					(thickness 0.15)
				)
				(justify left bottom)
				(hide yes)
			)
		)
		(property "License" "Apache-2.0"
			(at 129.54 21.59 0)
			(effects
				(font
					(size 1.27 1.27)
					(thickness 0.15)
				)
				(justify left bottom)
				(hide yes)
			)
		)
		(pin "1"
		)
		(pin "2"
		)
		(pin "3"
		)
		(pin "4"
		)
		(pin "5"
		)
		(pin "6"
		)
		(pin "7"
		)
		(pin "8"
		)
		(instances
			(project "jetson-orin-baseboard"
				(path ""
					(reference "R33")
					(unit 1)
				)
			)
		)
	)
	(symbol
		(lib_name "R_10k_0402_2")
		(lib_id "antmicroResistors0402:R_10k_0402")
		(at 30.48 64.77 0)
		(unit 1)
		(exclude_from_sim no)
		(in_bom yes)
		(on_board yes)
		(dnp no)
		(property "Reference" "R42"
			(at 35.56 64.135 0)
			(effects
				(font
					(size 1.27 1.27)
				)
				(justify left bottom)
			)
		)
		(property "Value" "R_10k_0402"
			(at 50.8 77.47 0)
			(effects
				(font
					(size 1.27 1.27)
					(thickness 0.15)
				)
				(justify left bottom)
				(hide yes)
			)
		)
		(property "Footprint" "antmicro-footprints:R_0402_1005Metric"
			(at 50.8 80.01 0)
			(effects
				(font
					(size 1.27 1.27)
					(thickness 0.15)
				)
				(justify left bottom)
				(hide yes)
			)
		)
		(property "Datasheet" "https://www.bourns.com/docs/product-datasheets/cr.pdf"
			(at 50.8 82.55 0)
			(effects
				(font
					(size 1.27 1.27)
					(thickness 0.15)
				)
				(justify left bottom)
				(hide yes)
			)
		)
		(property "Description" ""
			(at 30.48 64.77 0)
			(effects
				(font
					(size 1.27 1.27)
				)
				(hide yes)
			)
		)
		(property "Manufacturer" "Bourns"
			(at 50.8 87.63 0)
			(effects
				(font
					(size 1.27 1.27)
					(thickness 0.15)
				)
				(justify left bottom)
				(hide yes)
			)
		)
		(property "MPN" "CR0402-FX-1002GLF"
			(at 50.8 85.09 0)
			(effects
				(font
					(size 1.27 1.27)
					(thickness 0.15)
				)
				(justify left bottom)
				(hide yes)
			)
		)
		(property "Val" "10k"
			(at 27.305 64.135 0)
			(effects
				(font
					(size 1.27 1.27)
					(thickness 0.15)
				)
				(justify left bottom)
			)
		)
		(property "License" "Apache-2.0"
			(at 50.8 90.17 0)
			(effects
				(font
					(size 1.27 1.27)
					(thickness 0.15)
				)
				(justify left bottom)
				(hide yes)
			)
		)
		(property "Author" "Antmicro"
			(at 50.8 92.71 0)
			(effects
				(font
					(size 1.27 1.27)
					(thickness 0.15)
				)
				(justify left bottom)
				(hide yes)
			)
		)
		(property "Tolerance" "1%"
			(at 50.8 74.93 0)
			(effects
				(font
					(size 1.27 1.27)
				)
				(justify left bottom)
				(hide yes)
			)
		)
		(pin "1"
		)
		(pin "2"
		)
		(instances
			(project "jetson-orin-baseboard"
				(path ""
					(reference "R42")
					(unit 1)
				)
			)
		)
	)
	(symbol
		(lib_name "GND_3")
		(lib_id "antmicropower:GND")
		(at 316.23 59.69 0)
		(mirror y)
		(unit 1)
		(exclude_from_sim no)
		(in_bom yes)
		(on_board yes)
		(dnp no)
		(property "Reference" "#PWR095"
			(at 316.23 66.04 0)
			(effects
				(font
					(size 1.27 1.27)
				)
				(justify left bottom)
				(hide yes)
			)
		)
		(property "Value" "GND"
			(at 316.23 63.5 0)
			(effects
				(font
					(size 1.27 1.27)
					(thickness 0.15)
				)
			)
		)
		(property "Footprint" ""
			(at 307.34 67.31 0)
			(effects
				(font
					(size 1.27 1.27)
					(thickness 0.15)
				)
				(justify left bottom)
				(hide yes)
			)
		)
		(property "Datasheet" ""
			(at 307.34 72.39 0)
			(effects
				(font
					(size 1.27 1.27)
					(thickness 0.15)
				)
				(justify left bottom)
				(hide yes)
			)
		)
		(property "Description" ""
			(at 316.23 59.69 0)
			(effects
				(font
					(size 1.27 1.27)
				)
				(hide yes)
			)
		)
		(property "Author" "Antmicro"
			(at 307.34 67.31 0)
			(effects
				(font
					(size 1.27 1.27)
					(thickness 0.15)
				)
				(justify left bottom)
				(hide yes)
			)
		)
		(property "License" "Apache-2.0"
			(at 307.34 69.85 0)
			(effects
				(font
					(size 1.27 1.27)
					(thickness 0.15)
				)
				(justify left bottom)
				(hide yes)
			)
		)
		(pin "1"
		)
		(instances
			(project "jetson-orin-baseboard"
				(path ""
					(reference "#PWR095")
					(unit 1)
				)
			)
		)
	)
	(symbol
		(lib_id "antmicroTransistorsFETsMOSFETsSingle:PJE138K")
		(at 33.02 251.46 0)
		(unit 1)
		(exclude_from_sim no)
		(in_bom yes)
		(on_board yes)
		(dnp no)
		(fields_autoplaced yes)
		(property "Reference" "Q20"
			(at 43.18 247.65 0)
			(effects
				(font
					(size 1.27 1.27)
					(thickness 0.15)
				)
				(justify left)
			)
		)
		(property "Value" "PJE138K"
			(at 55.88 260.35 0)
			(effects
				(font
					(size 1.27 1.27)
					(thickness 0.15)
				)
				(justify left bottom)
				(hide yes)
			)
		)
		(property "Footprint" "antmicro-footprints:SOT-523"
			(at 55.88 262.89 0)
			(effects
				(font
					(size 1.27 1.27)
					(thickness 0.15)
				)
				(justify left bottom)
				(hide yes)
			)
		)
		(property "Datasheet" "https://www.mouser.com/datasheet/2/1057/PJE138K-1876698.pdf"
			(at 55.88 265.43 0)
			(effects
				(font
					(size 1.27 1.27)
					(thickness 0.15)
				)
				(justify left bottom)
				(hide yes)
			)
		)
		(property "Description" ""
			(at 33.02 251.46 0)
			(effects
				(font
					(size 1.27 1.27)
				)
				(hide yes)
			)
		)
		(property "MPN" "PJE138K_R1_00001"
			(at 43.18 250.19 0)
			(effects
				(font
					(size 1.27 1.27)
					(thickness 0.15)
				)
				(justify left)
			)
		)
		(property "Manufacturer" "PANJIT"
			(at 55.88 270.51 0)
			(effects
				(font
					(size 1.27 1.27)
					(thickness 0.15)
				)
				(justify left bottom)
				(hide yes)
			)
		)
		(property "Author" "Antmicro"
			(at 55.88 273.05 0)
			(effects
				(font
					(size 1.27 1.27)
					(thickness 0.15)
				)
				(justify left bottom)
				(hide yes)
			)
		)
		(property "License" "Apache-2.0"
			(at 55.88 275.59 0)
			(effects
				(font
					(size 1.27 1.27)
					(thickness 0.15)
				)
				(justify left bottom)
				(hide yes)
			)
		)
		(pin "1"
		)
		(pin "2"
		)
		(pin "3"
		)
		(instances
			(project "jetson-orin-baseboard"
				(path ""
					(reference "Q20")
					(unit 1)
				)
			)
		)
	)
	(symbol
		(lib_id "antmicroTVSDiodes:TPD4E05U06QDQARQ1")
		(at 349.25 135.89 270)
		(unit 1)
		(exclude_from_sim no)
		(in_bom yes)
		(on_board yes)
		(dnp no)
		(fields_autoplaced yes)
		(property "Reference" "U15"
			(at 344.805 147.32 90)
			(effects
				(font
					(size 1.27 1.27)
				)
			)
		)
		(property "Value" "TPD4E05U06QDQARQ1"
			(at 339.09 160.02 0)
			(effects
				(font
					(size 1.27 1.27)
					(thickness 0.15)
				)
				(justify left bottom)
				(hide yes)
			)
		)
		(property "Footprint" "antmicro-footprints:USON-10_2.5x1mm_P0.5mm"
			(at 344.17 160.02 0)
			(effects
				(font
					(size 1.27 1.27)
					(thickness 0.15)
				)
				(justify left bottom)
				(hide yes)
			)
		)
		(property "Datasheet" "https://www.ti.com/lit/ds/symlink/tpd4e05u06-q1.pdf?HQS=dis-mous-null-mousermode-dsf-pf-null-wwe&ts=1663591265741&ref_url=https%253A%252F%252Fwww.mouser.com%252F"
			(at 341.63 160.02 0)
			(effects
				(font
					(size 1.27 1.27)
					(thickness 0.15)
				)
				(justify left bottom)
				(hide yes)
			)
		)
		(property "Description" ""
			(at 349.25 135.89 0)
			(effects
				(font
					(size 1.27 1.27)
				)
				(hide yes)
			)
		)
		(property "Manufacturer" "Texas Instruments"
			(at 336.55 160.02 0)
			(effects
				(font
					(size 1.27 1.27)
					(thickness 0.15)
				)
				(justify left bottom)
				(hide yes)
			)
		)
		(property "MPN" "TPD4E05U06QDQARQ1"
			(at 344.805 149.86 90)
			(effects
				(font
					(size 1.27 1.27)
					(thickness 0.15)
				)
			)
		)
		(property "Author" "Antmicro"
			(at 334.01 160.02 0)
			(effects
				(font
					(size 1.27 1.27)
					(thickness 0.15)
				)
				(justify left bottom)
				(hide yes)
			)
		)
		(property "License" "Apache-2.0"
			(at 331.47 160.02 0)
			(effects
				(font
					(size 1.27 1.27)
					(thickness 0.15)
				)
				(justify left bottom)
				(hide yes)
			)
		)
		(pin "1"
		)
		(pin "10"
		)
		(pin "2"
		)
		(pin "3"
		)
		(pin "4"
		)
		(pin "5"
		)
		(pin "6"
		)
		(pin "7"
		)
		(pin "8"
		)
		(pin "9"
		)
		(instances
			(project "jetson-orin-baseboard"
				(path ""
					(reference "U15")
					(unit 1)
				)
			)
		)
	)
	(symbol
		(lib_name "LED_G_0603_LTST-C190GKT_4")
		(lib_id "antmicroLEDIndicationDiscrete:LED_G_0603_LTST-C190GKT")
		(at 111.76 204.47 270)
		(mirror x)
		(unit 1)
		(exclude_from_sim no)
		(in_bom yes)
		(on_board yes)
		(dnp no)
		(property "Reference" "D3"
			(at 109.855 200.66 90)
			(effects
				(font
					(size 1.27 1.27)
				)
				(justify right)
			)
		)
		(property "Value" "LED_G_0603_LTST-C190GKT"
			(at 104.14 181.61 0)
			(effects
				(font
					(size 1.27 1.27)
					(thickness 0.15)
				)
				(justify left bottom)
				(hide yes)
			)
		)
		(property "Footprint" "antmicro-footprints:LED_0603_1608Metric_G"
			(at 101.6 181.61 0)
			(effects
				(font
					(size 1.27 1.27)
					(thickness 0.15)
				)
				(justify left bottom)
				(hide yes)
			)
		)
		(property "Datasheet" "https://media.digikey.com/pdf/Data%20Sheets/Lite-On%20PDFs/LTST-C190GKT.pdf"
			(at 99.06 181.61 0)
			(effects
				(font
					(size 1.27 1.27)
					(thickness 0.15)
				)
				(justify left bottom)
				(hide yes)
			)
		)
		(property "Description" ""
			(at 111.76 204.47 0)
			(effects
				(font
					(size 1.27 1.27)
				)
				(hide yes)
			)
		)
		(property "MPN" "LTST-C190GKT"
			(at 96.52 181.61 0)
			(effects
				(font
					(size 1.27 1.27)
					(thickness 0.15)
				)
				(justify left bottom)
				(hide yes)
			)
		)
		(property "Manufacturer" "Lite-On"
			(at 93.98 181.61 0)
			(effects
				(font
					(size 1.27 1.27)
					(thickness 0.15)
				)
				(justify left bottom)
				(hide yes)
			)
		)
		(property "Author" "Antmicro"
			(at 91.44 181.61 0)
			(effects
				(font
					(size 1.27 1.27)
					(thickness 0.15)
				)
				(justify left bottom)
				(hide yes)
			)
		)
		(property "License" "Apache-2.0"
			(at 88.9 181.61 0)
			(effects
				(font
					(size 1.27 1.27)
					(thickness 0.15)
				)
				(justify left bottom)
				(hide yes)
			)
		)
		(property "Color" "Green"
			(at 109.855 203.2 90)
			(effects
				(font
					(size 1.27 1.27)
				)
				(justify right)
			)
		)
		(pin "1"
		)
		(pin "2"
		)
		(instances
			(project "jetson-orin-baseboard"
				(path ""
					(reference "D3")
					(unit 1)
				)
			)
		)
	)
	(symbol
		(lib_name "GND_3")
		(lib_id "antmicropower:GND")
		(at 274.32 173.99 0)
		(mirror y)
		(unit 1)
		(exclude_from_sim no)
		(in_bom yes)
		(on_board yes)
		(dnp no)
		(property "Reference" "#PWR089"
			(at 274.32 180.34 0)
			(effects
				(font
					(size 1.27 1.27)
				)
				(justify left bottom)
				(hide yes)
			)
		)
		(property "Value" "GND"
			(at 274.32 177.8 0)
			(effects
				(font
					(size 1.27 1.27)
					(thickness 0.15)
				)
			)
		)
		(property "Footprint" ""
			(at 265.43 181.61 0)
			(effects
				(font
					(size 1.27 1.27)
					(thickness 0.15)
				)
				(justify left bottom)
				(hide yes)
			)
		)
		(property "Datasheet" ""
			(at 265.43 186.69 0)
			(effects
				(font
					(size 1.27 1.27)
					(thickness 0.15)
				)
				(justify left bottom)
				(hide yes)
			)
		)
		(property "Description" ""
			(at 274.32 173.99 0)
			(effects
				(font
					(size 1.27 1.27)
				)
				(hide yes)
			)
		)
		(property "Author" "Antmicro"
			(at 265.43 181.61 0)
			(effects
				(font
					(size 1.27 1.27)
					(thickness 0.15)
				)
				(justify left bottom)
				(hide yes)
			)
		)
		(property "License" "Apache-2.0"
			(at 265.43 184.15 0)
			(effects
				(font
					(size 1.27 1.27)
					(thickness 0.15)
				)
				(justify left bottom)
				(hide yes)
			)
		)
		(pin "1"
		)
		(instances
			(project "jetson-orin-baseboard"
				(path ""
					(reference "#PWR089")
					(unit 1)
				)
			)
		)
	)
	(symbol
		(lib_name "GND_3")
		(lib_id "antmicropower:GND")
		(at 262.89 71.12 0)
		(mirror y)
		(unit 1)
		(exclude_from_sim no)
		(in_bom yes)
		(on_board yes)
		(dnp no)
		(property "Reference" "#PWR0256"
			(at 262.89 77.47 0)
			(effects
				(font
					(size 1.27 1.27)
				)
				(justify left bottom)
				(hide yes)
			)
		)
		(property "Value" "GND"
			(at 262.89 74.93 0)
			(effects
				(font
					(size 1.27 1.27)
					(thickness 0.15)
				)
			)
		)
		(property "Footprint" ""
			(at 254 78.74 0)
			(effects
				(font
					(size 1.27 1.27)
					(thickness 0.15)
				)
				(justify left bottom)
				(hide yes)
			)
		)
		(property "Datasheet" ""
			(at 254 83.82 0)
			(effects
				(font
					(size 1.27 1.27)
					(thickness 0.15)
				)
				(justify left bottom)
				(hide yes)
			)
		)
		(property "Description" ""
			(at 262.89 71.12 0)
			(effects
				(font
					(size 1.27 1.27)
				)
				(hide yes)
			)
		)
		(property "Author" "Antmicro"
			(at 254 78.74 0)
			(effects
				(font
					(size 1.27 1.27)
					(thickness 0.15)
				)
				(justify left bottom)
				(hide yes)
			)
		)
		(property "License" "Apache-2.0"
			(at 254 81.28 0)
			(effects
				(font
					(size 1.27 1.27)
					(thickness 0.15)
				)
				(justify left bottom)
				(hide yes)
			)
		)
		(pin "1"
		)
		(instances
			(project "jetson-orin-baseboard"
				(path ""
					(reference "#PWR0256")
					(unit 1)
				)
			)
		)
	)
	(symbol
		(lib_id "antmicroInterfaceControllers:FT230X_QFN")
		(at 46.99 201.93 0)
		(unit 1)
		(exclude_from_sim no)
		(in_bom yes)
		(on_board yes)
		(dnp no)
		(fields_autoplaced yes)
		(property "Reference" "U5"
			(at 58.42 194.31 0)
			(effects
				(font
					(size 1.27 1.27)
				)
			)
		)
		(property "Value" "FT230X_QFN"
			(at 86.36 212.09 0)
			(effects
				(font
					(size 1.27 1.27)
					(thickness 0.15)
				)
				(justify left bottom)
				(hide yes)
			)
		)
		(property "Footprint" "antmicro-footprints:QFN-16-1EP_4x4mm_P0.65mm"
			(at 86.36 214.63 0)
			(effects
				(font
					(size 1.27 1.27)
					(thickness 0.15)
				)
				(justify left bottom)
				(hide yes)
			)
		)
		(property "Datasheet" "https://ftdichip.com/wp-content/uploads/2021/10/DS_FT230X.pdf"
			(at 86.36 217.17 0)
			(effects
				(font
					(size 1.27 1.27)
					(thickness 0.15)
				)
				(justify left bottom)
				(hide yes)
			)
		)
		(property "Description" ""
			(at 46.99 201.93 0)
			(effects
				(font
					(size 1.27 1.27)
				)
				(hide yes)
			)
		)
		(property "Manufacturer" "FTDI Chip"
			(at 86.36 219.71 0)
			(effects
				(font
					(size 1.27 1.27)
					(thickness 0.15)
				)
				(justify left bottom)
				(hide yes)
			)
		)
		(property "MPN" "FT230XQ-R"
			(at 58.42 196.85 0)
			(effects
				(font
					(size 1.27 1.27)
					(thickness 0.15)
				)
			)
		)
		(property "Author" "Antmicro"
			(at 86.36 224.79 0)
			(effects
				(font
					(size 1.27 1.27)
					(thickness 0.15)
				)
				(justify left bottom)
				(hide yes)
			)
		)
		(property "License" "Apache-2.0"
			(at 86.36 227.33 0)
			(effects
				(font
					(size 1.27 1.27)
					(thickness 0.15)
				)
				(justify left bottom)
				(hide yes)
			)
		)
		(pin "1"
		)
		(pin "10"
		)
		(pin "11"
		)
		(pin "12"
		)
		(pin "13"
		)
		(pin "14"
		)
		(pin "15"
		)
		(pin "16"
		)
		(pin "17"
		)
		(pin "2"
		)
		(pin "3"
		)
		(pin "4"
		)
		(pin "5"
		)
		(pin "6"
		)
		(pin "7"
		)
		(pin "8"
		)
		(pin "9"
		)
		(instances
			(project "jetson-orin-baseboard"
				(path ""
					(reference "U5")
					(unit 1)
				)
			)
		)
	)
	(symbol
		(lib_name "R_200R_0402_1")
		(lib_id "antmicroResistors0402:R_200R_0402")
		(at 118.11 85.09 0)
		(unit 1)
		(exclude_from_sim no)
		(in_bom yes)
		(on_board yes)
		(dnp no)
		(property "Reference" "R69"
			(at 123.19 84.455 0)
			(effects
				(font
					(size 1.27 1.27)
				)
				(justify left bottom)
			)
		)
		(property "Value" "R_200R_0402"
			(at 138.43 97.79 0)
			(effects
				(font
					(size 1.27 1.27)
					(thickness 0.15)
				)
				(justify left bottom)
				(hide yes)
			)
		)
		(property "Footprint" "antmicro-footprints:R_0402_1005Metric"
			(at 138.43 100.33 0)
			(effects
				(font
					(size 1.27 1.27)
					(thickness 0.15)
				)
				(justify left bottom)
				(hide yes)
			)
		)
		(property "Datasheet" "https://www.bourns.com/docs/product-datasheets/cr.pdf"
			(at 138.43 102.87 0)
			(effects
				(font
					(size 1.27 1.27)
					(thickness 0.15)
				)
				(justify left bottom)
				(hide yes)
			)
		)
		(property "Description" ""
			(at 118.11 85.09 0)
			(effects
				(font
					(size 1.27 1.27)
				)
				(hide yes)
			)
		)
		(property "Manufacturer" "Bourns"
			(at 138.43 107.95 0)
			(effects
				(font
					(size 1.27 1.27)
					(thickness 0.15)
				)
				(justify left bottom)
				(hide yes)
			)
		)
		(property "MPN" "CR0402-FX-2000GLF"
			(at 138.43 105.41 0)
			(effects
				(font
					(size 1.27 1.27)
					(thickness 0.15)
				)
				(justify left bottom)
				(hide yes)
			)
		)
		(property "Val" "200R"
			(at 113.03 84.455 0)
			(effects
				(font
					(size 1.27 1.27)
					(thickness 0.15)
				)
				(justify left bottom)
			)
		)
		(property "License" "Apache-2.0"
			(at 138.43 110.49 0)
			(effects
				(font
					(size 1.27 1.27)
					(thickness 0.15)
				)
				(justify left bottom)
				(hide yes)
			)
		)
		(property "Author" "Antmicro"
			(at 138.43 113.03 0)
			(effects
				(font
					(size 1.27 1.27)
					(thickness 0.15)
				)
				(justify left bottom)
				(hide yes)
			)
		)
		(property "Tolerance" "1%"
			(at 138.43 95.25 0)
			(effects
				(font
					(size 1.27 1.27)
				)
				(justify left bottom)
				(hide yes)
			)
		)
		(pin "1"
		)
		(pin "2"
		)
		(instances
			(project "jetson-orin-baseboard"
				(path ""
					(reference "R69")
					(unit 1)
				)
			)
		)
	)
	(symbol
		(lib_id "antmicroDiodesRectifiersSingle:RB521S30T1G")
		(at 63.5 123.19 180)
		(unit 1)
		(exclude_from_sim no)
		(in_bom yes)
		(on_board yes)
		(dnp no)
		(fields_autoplaced yes)
		(property "Reference" "D35"
			(at 60.96 116.84 0)
			(effects
				(font
					(size 1.27 1.27)
				)
			)
		)
		(property "Value" "RB521S30T1G"
			(at 40.64 107.95 0)
			(effects
				(font
					(size 1.27 1.27)
					(thickness 0.15)
				)
				(justify left bottom)
				(hide yes)
			)
		)
		(property "Footprint" "antmicro-footprints:SOD-523"
			(at 40.64 113.03 0)
			(effects
				(font
					(size 1.27 1.27)
					(thickness 0.15)
				)
				(justify left bottom)
				(hide yes)
			)
		)
		(property "Datasheet" "https://www.onsemi.com/pdf/datasheet/rb521s30t1-d.pdf"
			(at 40.64 110.49 0)
			(effects
				(font
					(size 1.27 1.27)
					(thickness 0.15)
				)
				(justify left bottom)
				(hide yes)
			)
		)
		(property "Description" ""
			(at 63.5 123.19 0)
			(effects
				(font
					(size 1.27 1.27)
				)
				(hide yes)
			)
		)
		(property "MPN" "RB521S30T1G"
			(at 60.96 119.38 0)
			(effects
				(font
					(size 1.27 1.27)
					(thickness 0.15)
				)
			)
		)
		(property "Manufacturer" "ON Semiconductor"
			(at 40.64 105.41 0)
			(effects
				(font
					(size 1.27 1.27)
					(thickness 0.15)
				)
				(justify left bottom)
				(hide yes)
			)
		)
		(property "Author" "Antmicro"
			(at 40.64 102.87 0)
			(effects
				(font
					(size 1.27 1.27)
					(thickness 0.15)
				)
				(justify left bottom)
				(hide yes)
			)
		)
		(property "License" "Apache-2.0"
			(at 40.64 100.33 0)
			(effects
				(font
					(size 1.27 1.27)
					(thickness 0.15)
				)
				(justify left bottom)
				(hide yes)
			)
		)
		(pin "1"
		)
		(pin "2"
		)
		(instances
			(project "jetson-orin-baseboard"
				(path ""
					(reference "D35")
					(unit 1)
				)
			)
		)
	)
	(symbol
		(lib_id "antmicropower:+3V3")
		(at 276.86 138.43 0)
		(unit 1)
		(exclude_from_sim no)
		(in_bom yes)
		(on_board yes)
		(dnp no)
		(property "Reference" "#PWR090"
			(at 276.86 142.24 0)
			(effects
				(font
					(size 1.27 1.27)
				)
				(justify left bottom)
				(hide yes)
			)
		)
		(property "Value" "+3V3"
			(at 273.685 134.62 0)
			(effects
				(font
					(size 1.27 1.27)
					(thickness 0.15)
				)
				(justify left)
			)
		)
		(property "Footprint" ""
			(at 292.1 146.05 0)
			(effects
				(font
					(size 1.27 1.27)
					(thickness 0.15)
				)
				(justify left bottom)
				(hide yes)
			)
		)
		(property "Datasheet" ""
			(at 292.1 148.59 0)
			(effects
				(font
					(size 1.27 1.27)
					(thickness 0.15)
				)
				(justify left bottom)
				(hide yes)
			)
		)
		(property "Description" ""
			(at 276.86 138.43 0)
			(effects
				(font
					(size 1.27 1.27)
				)
				(hide yes)
			)
		)
		(property "Author" "Antmicro"
			(at 292.1 140.97 0)
			(effects
				(font
					(size 1.27 1.27)
					(thickness 0.15)
				)
				(justify left bottom)
				(hide yes)
			)
		)
		(property "License" "Apache-2.0"
			(at 292.1 143.51 0)
			(effects
				(font
					(size 1.27 1.27)
					(thickness 0.15)
				)
				(justify left bottom)
				(hide yes)
			)
		)
		(pin "1"
		)
		(instances
			(project "jetson-orin-baseboard"
				(path ""
					(reference "#PWR090")
					(unit 1)
				)
			)
		)
	)
	(symbol
		(lib_name "GND_3")
		(lib_id "antmicropower:GND")
		(at 29.21 180.34 0)
		(mirror y)
		(unit 1)
		(exclude_from_sim no)
		(in_bom yes)
		(on_board yes)
		(dnp no)
		(property "Reference" "#PWR061"
			(at 29.21 186.69 0)
			(effects
				(font
					(size 1.27 1.27)
				)
				(justify left bottom)
				(hide yes)
			)
		)
		(property "Value" "GND"
			(at 29.21 184.15 0)
			(effects
				(font
					(size 1.27 1.27)
					(thickness 0.15)
				)
			)
		)
		(property "Footprint" ""
			(at 20.32 187.96 0)
			(effects
				(font
					(size 1.27 1.27)
					(thickness 0.15)
				)
				(justify left bottom)
				(hide yes)
			)
		)
		(property "Datasheet" ""
			(at 20.32 193.04 0)
			(effects
				(font
					(size 1.27 1.27)
					(thickness 0.15)
				)
				(justify left bottom)
				(hide yes)
			)
		)
		(property "Description" ""
			(at 29.21 180.34 0)
			(effects
				(font
					(size 1.27 1.27)
				)
				(hide yes)
			)
		)
		(property "Author" "Antmicro"
			(at 20.32 187.96 0)
			(effects
				(font
					(size 1.27 1.27)
					(thickness 0.15)
				)
				(justify left bottom)
				(hide yes)
			)
		)
		(property "License" "Apache-2.0"
			(at 20.32 190.5 0)
			(effects
				(font
					(size 1.27 1.27)
					(thickness 0.15)
				)
				(justify left bottom)
				(hide yes)
			)
		)
		(pin "1"
		)
		(instances
			(project "jetson-orin-baseboard"
				(path ""
					(reference "#PWR061")
					(unit 1)
				)
			)
		)
	)
	(symbol
		(lib_name "R_100k_0402_1")
		(lib_id "antmicroResistors0402:R_100k_0402")
		(at 30.48 67.31 0)
		(unit 1)
		(exclude_from_sim no)
		(in_bom yes)
		(on_board yes)
		(dnp no)
		(property "Reference" "R43"
			(at 35.56 66.675 0)
			(effects
				(font
					(size 1.27 1.27)
				)
				(justify left bottom)
			)
		)
		(property "Value" "R_100k_0402"
			(at 50.8 80.01 0)
			(effects
				(font
					(size 1.27 1.27)
					(thickness 0.15)
				)
				(justify left bottom)
				(hide yes)
			)
		)
		(property "Footprint" "antmicro-footprints:R_0402_1005Metric"
			(at 50.8 82.55 0)
			(effects
				(font
					(size 1.27 1.27)
					(thickness 0.15)
				)
				(justify left bottom)
				(hide yes)
			)
		)
		(property "Datasheet" "https://www.bourns.com/docs/product-datasheets/cr.pdf"
			(at 50.8 85.09 0)
			(effects
				(font
					(size 1.27 1.27)
					(thickness 0.15)
				)
				(justify left bottom)
				(hide yes)
			)
		)
		(property "Description" ""
			(at 30.48 67.31 0)
			(effects
				(font
					(size 1.27 1.27)
				)
				(hide yes)
			)
		)
		(property "Manufacturer" "Bourns"
			(at 50.8 90.17 0)
			(effects
				(font
					(size 1.27 1.27)
					(thickness 0.15)
				)
				(justify left bottom)
				(hide yes)
			)
		)
		(property "MPN" "CR0402-FX-1003GLF"
			(at 50.8 87.63 0)
			(effects
				(font
					(size 1.27 1.27)
					(thickness 0.15)
				)
				(justify left bottom)
				(hide yes)
			)
		)
		(property "Val" "100k"
			(at 26.035 66.675 0)
			(effects
				(font
					(size 1.27 1.27)
					(thickness 0.15)
				)
				(justify left bottom)
			)
		)
		(property "License" "Apache-2.0"
			(at 50.8 92.71 0)
			(effects
				(font
					(size 1.27 1.27)
					(thickness 0.15)
				)
				(justify left bottom)
				(hide yes)
			)
		)
		(property "Author" "Antmicro"
			(at 50.8 95.25 0)
			(effects
				(font
					(size 1.27 1.27)
					(thickness 0.15)
				)
				(justify left bottom)
				(hide yes)
			)
		)
		(property "Tolerance" "1%"
			(at 50.8 77.47 0)
			(effects
				(font
					(size 1.27 1.27)
				)
				(justify left bottom)
				(hide yes)
			)
		)
		(pin "1"
		)
		(pin "2"
		)
		(instances
			(project "jetson-orin-baseboard"
				(path ""
					(reference "R43")
					(unit 1)
				)
			)
		)
	)
	(symbol
		(lib_name "GND_3")
		(lib_id "antmicropower:GND")
		(at 190.5 73.66 0)
		(mirror y)
		(unit 1)
		(exclude_from_sim no)
		(in_bom yes)
		(on_board yes)
		(dnp no)
		(property "Reference" "#PWR076"
			(at 190.5 80.01 0)
			(effects
				(font
					(size 1.27 1.27)
				)
				(justify left bottom)
				(hide yes)
			)
		)
		(property "Value" "GND"
			(at 190.5 77.47 0)
			(effects
				(font
					(size 1.27 1.27)
					(thickness 0.15)
				)
			)
		)
		(property "Footprint" ""
			(at 181.61 81.28 0)
			(effects
				(font
					(size 1.27 1.27)
					(thickness 0.15)
				)
				(justify left bottom)
				(hide yes)
			)
		)
		(property "Datasheet" ""
			(at 181.61 86.36 0)
			(effects
				(font
					(size 1.27 1.27)
					(thickness 0.15)
				)
				(justify left bottom)
				(hide yes)
			)
		)
		(property "Description" ""
			(at 190.5 73.66 0)
			(effects
				(font
					(size 1.27 1.27)
				)
				(hide yes)
			)
		)
		(property "Author" "Antmicro"
			(at 181.61 81.28 0)
			(effects
				(font
					(size 1.27 1.27)
					(thickness 0.15)
				)
				(justify left bottom)
				(hide yes)
			)
		)
		(property "License" "Apache-2.0"
			(at 181.61 83.82 0)
			(effects
				(font
					(size 1.27 1.27)
					(thickness 0.15)
				)
				(justify left bottom)
				(hide yes)
			)
		)
		(pin "1"
		)
		(instances
			(project "jetson-orin-baseboard"
				(path ""
					(reference "#PWR076")
					(unit 1)
				)
			)
		)
	)
	(symbol
		(lib_name "GND_3")
		(lib_id "antmicropower:GND")
		(at 25.4 200.66 0)
		(mirror y)
		(unit 1)
		(exclude_from_sim no)
		(in_bom yes)
		(on_board yes)
		(dnp no)
		(property "Reference" "#PWR048"
			(at 25.4 207.01 0)
			(effects
				(font
					(size 1.27 1.27)
				)
				(justify left bottom)
				(hide yes)
			)
		)
		(property "Value" "GND"
			(at 25.4 204.47 0)
			(effects
				(font
					(size 1.27 1.27)
					(thickness 0.15)
				)
			)
		)
		(property "Footprint" ""
			(at 16.51 208.28 0)
			(effects
				(font
					(size 1.27 1.27)
					(thickness 0.15)
				)
				(justify left bottom)
				(hide yes)
			)
		)
		(property "Datasheet" ""
			(at 16.51 213.36 0)
			(effects
				(font
					(size 1.27 1.27)
					(thickness 0.15)
				)
				(justify left bottom)
				(hide yes)
			)
		)
		(property "Description" ""
			(at 25.4 200.66 0)
			(effects
				(font
					(size 1.27 1.27)
				)
				(hide yes)
			)
		)
		(property "Author" "Antmicro"
			(at 16.51 208.28 0)
			(effects
				(font
					(size 1.27 1.27)
					(thickness 0.15)
				)
				(justify left bottom)
				(hide yes)
			)
		)
		(property "License" "Apache-2.0"
			(at 16.51 210.82 0)
			(effects
				(font
					(size 1.27 1.27)
					(thickness 0.15)
				)
				(justify left bottom)
				(hide yes)
			)
		)
		(pin "1"
		)
		(instances
			(project "jetson-orin-baseboard"
				(path ""
					(reference "#PWR048")
					(unit 1)
				)
			)
		)
	)
	(symbol
		(lib_name "GND_3")
		(lib_id "antmicropower:GND")
		(at 346.71 231.14 0)
		(mirror y)
		(unit 1)
		(exclude_from_sim no)
		(in_bom yes)
		(on_board yes)
		(dnp no)
		(property "Reference" "#PWR092"
			(at 346.71 237.49 0)
			(effects
				(font
					(size 1.27 1.27)
				)
				(justify left bottom)
				(hide yes)
			)
		)
		(property "Value" "GND"
			(at 346.71 234.95 0)
			(effects
				(font
					(size 1.27 1.27)
					(thickness 0.15)
				)
			)
		)
		(property "Footprint" ""
			(at 337.82 238.76 0)
			(effects
				(font
					(size 1.27 1.27)
					(thickness 0.15)
				)
				(justify left bottom)
				(hide yes)
			)
		)
		(property "Datasheet" ""
			(at 337.82 243.84 0)
			(effects
				(font
					(size 1.27 1.27)
					(thickness 0.15)
				)
				(justify left bottom)
				(hide yes)
			)
		)
		(property "Description" ""
			(at 346.71 231.14 0)
			(effects
				(font
					(size 1.27 1.27)
				)
				(hide yes)
			)
		)
		(property "Author" "Antmicro"
			(at 337.82 238.76 0)
			(effects
				(font
					(size 1.27 1.27)
					(thickness 0.15)
				)
				(justify left bottom)
				(hide yes)
			)
		)
		(property "License" "Apache-2.0"
			(at 337.82 241.3 0)
			(effects
				(font
					(size 1.27 1.27)
					(thickness 0.15)
				)
				(justify left bottom)
				(hide yes)
			)
		)
		(pin "1"
		)
		(instances
			(project "jetson-orin-baseboard"
				(path ""
					(reference "#PWR092")
					(unit 1)
				)
			)
		)
	)
	(symbol
		(lib_name "LED_G_0603_LTST-C190GKT_1")
		(lib_id "antmicroLEDIndicationDiscrete:LED_G_0603_LTST-C190GKT")
		(at 134.62 85.09 0)
		(mirror y)
		(unit 1)
		(exclude_from_sim no)
		(in_bom yes)
		(on_board yes)
		(dnp no)
		(property "Reference" "D5"
			(at 134.62 84.455 0)
			(effects
				(font
					(size 1.27 1.27)
				)
				(justify right bottom)
			)
		)
		(property "Value" "LED_G_0603_LTST-C190GKT"
			(at 111.76 92.71 0)
			(effects
				(font
					(size 1.27 1.27)
					(thickness 0.15)
				)
				(justify left bottom)
				(hide yes)
			)
		)
		(property "Footprint" "antmicro-footprints:LED_0603_1608Metric_G"
			(at 111.76 95.25 0)
			(effects
				(font
					(size 1.27 1.27)
					(thickness 0.15)
				)
				(justify left bottom)
				(hide yes)
			)
		)
		(property "Datasheet" "https://media.digikey.com/pdf/Data%20Sheets/Lite-On%20PDFs/LTST-C190GKT.pdf"
			(at 111.76 97.79 0)
			(effects
				(font
					(size 1.27 1.27)
					(thickness 0.15)
				)
				(justify left bottom)
				(hide yes)
			)
		)
		(property "Description" ""
			(at 134.62 85.09 0)
			(effects
				(font
					(size 1.27 1.27)
				)
				(hide yes)
			)
		)
		(property "MPN" "LTST-C190GKT"
			(at 111.76 100.33 0)
			(effects
				(font
					(size 1.27 1.27)
					(thickness 0.15)
				)
				(justify left bottom)
				(hide yes)
			)
		)
		(property "Manufacturer" "Lite-On"
			(at 111.76 102.87 0)
			(effects
				(font
					(size 1.27 1.27)
					(thickness 0.15)
				)
				(justify left bottom)
				(hide yes)
			)
		)
		(property "Author" "Antmicro"
			(at 111.76 105.41 0)
			(effects
				(font
					(size 1.27 1.27)
					(thickness 0.15)
				)
				(justify left bottom)
				(hide yes)
			)
		)
		(property "License" "Apache-2.0"
			(at 111.76 107.95 0)
			(effects
				(font
					(size 1.27 1.27)
					(thickness 0.15)
				)
				(justify left bottom)
				(hide yes)
			)
		)
		(property "Color" "Green"
			(at 128.905 88.265 0)
			(effects
				(font
					(size 1.27 1.27)
				)
				(justify right bottom)
			)
		)
		(pin "1"
		)
		(pin "2"
		)
		(instances
			(project "jetson-orin-baseboard"
				(path ""
					(reference "D5")
					(unit 1)
				)
			)
		)
	)
	(symbol
		(lib_id "antmicroLEDIndicationDiscrete:LED_G_0603_LTST-C190GKT")
		(at 396.24 53.34 90)
		(unit 1)
		(exclude_from_sim no)
		(in_bom yes)
		(on_board yes)
		(dnp no)
		(property "Reference" "D9"
			(at 398.145 49.53 90)
			(effects
				(font
					(size 1.27 1.27)
				)
				(justify right)
			)
		)
		(property "Value" "LED_G_0603_LTST-C190GKT"
			(at 403.86 30.48 0)
			(effects
				(font
					(size 1.27 1.27)
					(thickness 0.15)
				)
				(justify left bottom)
				(hide yes)
			)
		)
		(property "Footprint" "antmicro-footprints:LED_0603_1608Metric_G"
			(at 406.4 30.48 0)
			(effects
				(font
					(size 1.27 1.27)
					(thickness 0.15)
				)
				(justify left bottom)
				(hide yes)
			)
		)
		(property "Datasheet" "https://media.digikey.com/pdf/Data%20Sheets/Lite-On%20PDFs/LTST-C190GKT.pdf"
			(at 408.94 30.48 0)
			(effects
				(font
					(size 1.27 1.27)
					(thickness 0.15)
				)
				(justify left bottom)
				(hide yes)
			)
		)
		(property "Description" ""
			(at 396.24 53.34 0)
			(effects
				(font
					(size 1.27 1.27)
				)
				(hide yes)
			)
		)
		(property "MPN" "LTST-C190GKT"
			(at 411.48 30.48 0)
			(effects
				(font
					(size 1.27 1.27)
					(thickness 0.15)
				)
				(justify left bottom)
				(hide yes)
			)
		)
		(property "Manufacturer" "Lite-On"
			(at 414.02 30.48 0)
			(effects
				(font
					(size 1.27 1.27)
					(thickness 0.15)
				)
				(justify left bottom)
				(hide yes)
			)
		)
		(property "Author" "Antmicro"
			(at 416.56 30.48 0)
			(effects
				(font
					(size 1.27 1.27)
					(thickness 0.15)
				)
				(justify left bottom)
				(hide yes)
			)
		)
		(property "License" "Apache-2.0"
			(at 419.1 30.48 0)
			(effects
				(font
					(size 1.27 1.27)
					(thickness 0.15)
				)
				(justify left bottom)
				(hide yes)
			)
		)
		(property "Color" "Green"
			(at 398.145 52.07 90)
			(effects
				(font
					(size 1.27 1.27)
				)
				(justify right)
			)
		)
		(pin "1"
		)
		(pin "2"
		)
		(instances
			(project "jetson-orin-baseboard"
				(path ""
					(reference "D9")
					(unit 1)
				)
			)
		)
	)
	(symbol
		(lib_id "antmicroCapacitors0402:C_100n_0402")
		(at 200.66 67.31 90)
		(mirror x)
		(unit 1)
		(exclude_from_sim no)
		(in_bom yes)
		(on_board yes)
		(dnp no)
		(property "Reference" "C55"
			(at 203.2 68.5863 90)
			(effects
				(font
					(size 1.27 1.27)
				)
				(justify right)
			)
		)
		(property "Value" "C_100n_0402"
			(at 210.82 87.63 0)
			(effects
				(font
					(size 1.27 1.27)
					(thickness 0.15)
				)
				(justify left bottom)
				(hide yes)
			)
		)
		(property "Footprint" "antmicro-footprints:C_0402_1005Metric"
			(at 213.36 87.63 0)
			(effects
				(font
					(size 1.27 1.27)
					(thickness 0.15)
				)
				(justify left bottom)
				(hide yes)
			)
		)
		(property "Datasheet" "https://www.murata.com/products/productdetail?partno=GRM155R61H104KE14%23"
			(at 215.9 87.63 0)
			(effects
				(font
					(size 1.27 1.27)
					(thickness 0.15)
				)
				(justify left bottom)
				(hide yes)
			)
		)
		(property "Description" ""
			(at 200.66 67.31 0)
			(effects
				(font
					(size 1.27 1.27)
				)
				(hide yes)
			)
		)
		(property "Manufacturer" "Murata"
			(at 220.98 87.63 0)
			(effects
				(font
					(size 1.27 1.27)
					(thickness 0.15)
				)
				(justify left bottom)
				(hide yes)
			)
		)
		(property "MPN" "GRM155R61H104KE14D"
			(at 218.44 87.63 0)
			(effects
				(font
					(size 1.27 1.27)
					(thickness 0.15)
				)
				(justify left bottom)
				(hide yes)
			)
		)
		(property "Val" "100n"
			(at 203.2 71.1263 90)
			(effects
				(font
					(size 1.27 1.27)
					(thickness 0.15)
				)
				(justify right)
			)
		)
		(property "License" "Apache-2.0"
			(at 223.52 87.63 0)
			(effects
				(font
					(size 1.27 1.27)
					(thickness 0.15)
				)
				(justify left bottom)
				(hide yes)
			)
		)
		(property "Author" "Antmicro"
			(at 226.06 87.63 0)
			(effects
				(font
					(size 1.27 1.27)
					(thickness 0.15)
				)
				(justify left bottom)
				(hide yes)
			)
		)
		(property "Voltage" "50V"
			(at 228.6 87.63 0)
			(effects
				(font
					(size 1.27 1.27)
				)
				(justify left bottom)
				(hide yes)
			)
		)
		(property "Dielectric" "X5R"
			(at 231.14 87.63 0)
			(effects
				(font
					(size 1.27 1.27)
				)
				(justify left bottom)
				(hide yes)
			)
		)
		(pin "1"
		)
		(pin "2"
		)
		(instances
			(project "jetson-orin-baseboard"
				(path ""
					(reference "C55")
					(unit 1)
				)
			)
		)
	)
	(symbol
		(lib_id "antmicroUSBConnectors:USB-C_WE_632723300011")
		(at 372.11 73.66 0)
		(mirror y)
		(unit 1)
		(exclude_from_sim no)
		(in_bom yes)
		(on_board yes)
		(dnp no)
		(property "Reference" "J4"
			(at 385.445 67.31 0)
			(effects
				(font
					(size 1.27 1.27)
				)
			)
		)
		(property "Value" "USB-C_WE_632723300011"
			(at 356.87 81.28 0)
			(effects
				(font
					(size 1.27 1.27)
					(thickness 0.15)
				)
				(justify left bottom)
				(hide yes)
			)
		)
		(property "Footprint" "antmicro-footprints:USB-C_Receptacle_WE_632723300011"
			(at 356.87 83.82 0)
			(effects
				(font
					(size 1.27 1.27)
					(thickness 0.15)
				)
				(justify left bottom)
				(hide yes)
			)
		)
		(property "Datasheet" "https://www.we-online.com/components/products/datasheet/632723300011.pdf"
			(at 356.87 86.36 0)
			(effects
				(font
					(size 1.27 1.27)
					(thickness 0.15)
				)
				(justify left bottom)
				(hide yes)
			)
		)
		(property "Description" ""
			(at 372.11 73.66 0)
			(effects
				(font
					(size 1.27 1.27)
				)
				(hide yes)
			)
		)
		(property "Manufacturer" "Würth Elektronik"
			(at 356.87 88.9 0)
			(effects
				(font
					(size 1.27 1.27)
					(thickness 0.15)
				)
				(justify left bottom)
				(hide yes)
			)
		)
		(property "MPN" "632723300011"
			(at 385.445 69.85 0)
			(effects
				(font
					(size 1.27 1.27)
					(thickness 0.15)
				)
			)
		)
		(property "Author" "Antmicro"
			(at 356.87 91.44 0)
			(effects
				(font
					(size 1.27 1.27)
					(thickness 0.15)
				)
				(justify left bottom)
				(hide yes)
			)
		)
		(property "License" "Apache-2.0"
			(at 356.87 93.98 0)
			(effects
				(font
					(size 1.27 1.27)
					(thickness 0.15)
				)
				(justify left bottom)
				(hide yes)
			)
		)
		(pin "A1"
		)
		(pin "A10"
		)
		(pin "A11"
		)
		(pin "A12"
		)
		(pin "A2"
		)
		(pin "A3"
		)
		(pin "A4"
		)
		(pin "A5"
		)
		(pin "A6"
		)
		(pin "A7"
		)
		(pin "A8"
		)
		(pin "A9"
		)
		(pin "B1"
		)
		(pin "B10"
		)
		(pin "B11"
		)
		(pin "B12"
		)
		(pin "B2"
		)
		(pin "B3"
		)
		(pin "B4"
		)
		(pin "B5"
		)
		(pin "B6"
		)
		(pin "B7"
		)
		(pin "B8"
		)
		(pin "B9"
		)
		(pin "SH"
		)
		(instances
			(project "jetson-orin-baseboard"
				(path ""
					(reference "J4")
					(unit 1)
				)
			)
		)
	)
	(symbol
		(lib_name "R_2k2_0402_1")
		(lib_id "antmicroResistors0402:R_2k2_0402")
		(at 229.87 215.9 90)
		(unit 1)
		(exclude_from_sim no)
		(in_bom yes)
		(on_board yes)
		(dnp no)
		(property "Reference" "R78"
			(at 231.14 212.09 90)
			(effects
				(font
					(size 1.27 1.27)
				)
				(justify right)
			)
		)
		(property "Value" "R_2k2_0402"
			(at 242.57 195.58 0)
			(effects
				(font
					(size 1.27 1.27)
					(thickness 0.15)
				)
				(justify left bottom)
				(hide yes)
			)
		)
		(property "Footprint" "antmicro-footprints:R_0402_1005Metric"
			(at 245.11 195.58 0)
			(effects
				(font
					(size 1.27 1.27)
					(thickness 0.15)
				)
				(justify left bottom)
				(hide yes)
			)
		)
		(property "Datasheet" "https://www.bourns.com/docs/product-datasheets/cr.pdf"
			(at 247.65 195.58 0)
			(effects
				(font
					(size 1.27 1.27)
					(thickness 0.15)
				)
				(justify left bottom)
				(hide yes)
			)
		)
		(property "Description" ""
			(at 229.87 215.9 0)
			(effects
				(font
					(size 1.27 1.27)
				)
				(hide yes)
			)
		)
		(property "Manufacturer" "Bourns"
			(at 252.73 195.58 0)
			(effects
				(font
					(size 1.27 1.27)
					(thickness 0.15)
				)
				(justify left bottom)
				(hide yes)
			)
		)
		(property "MPN" "CR0402-FX-2201GLF"
			(at 250.19 195.58 0)
			(effects
				(font
					(size 1.27 1.27)
					(thickness 0.15)
				)
				(justify left bottom)
				(hide yes)
			)
		)
		(property "Val" "2k2"
			(at 231.14 214.63 90)
			(effects
				(font
					(size 1.27 1.27)
					(thickness 0.15)
				)
				(justify right)
			)
		)
		(property "License" "Apache-2.0"
			(at 255.27 195.58 0)
			(effects
				(font
					(size 1.27 1.27)
					(thickness 0.15)
				)
				(justify left bottom)
				(hide yes)
			)
		)
		(property "Author" "Antmicro"
			(at 257.81 195.58 0)
			(effects
				(font
					(size 1.27 1.27)
					(thickness 0.15)
				)
				(justify left bottom)
				(hide yes)
			)
		)
		(property "Tolerance" "1%"
			(at 240.03 195.58 0)
			(effects
				(font
					(size 1.27 1.27)
				)
				(justify left bottom)
				(hide yes)
			)
		)
		(pin "1"
		)
		(pin "2"
		)
		(instances
			(project "jetson-orin-baseboard"
				(path ""
					(reference "R78")
					(unit 1)
				)
			)
		)
	)
	(symbol
		(lib_name "C_100n_0402_8")
		(lib_id "antmicroCapacitors0402:C_100n_0402")
		(at 173.99 201.93 90)
		(mirror x)
		(unit 1)
		(exclude_from_sim no)
		(in_bom yes)
		(on_board yes)
		(dnp no)
		(fields_autoplaced yes)
		(property "Reference" "C45"
			(at 176.53 203.2063 90)
			(effects
				(font
					(size 1.27 1.27)
				)
				(justify right)
			)
		)
		(property "Value" "C_100n_0402"
			(at 184.15 222.25 0)
			(effects
				(font
					(size 1.27 1.27)
					(thickness 0.15)
				)
				(justify left bottom)
				(hide yes)
			)
		)
		(property "Footprint" "antmicro-footprints:C_0402_1005Metric"
			(at 186.69 222.25 0)
			(effects
				(font
					(size 1.27 1.27)
					(thickness 0.15)
				)
				(justify left bottom)
				(hide yes)
			)
		)
		(property "Datasheet" "https://www.murata.com/products/productdetail?partno=GRM155R61H104KE14%23"
			(at 189.23 222.25 0)
			(effects
				(font
					(size 1.27 1.27)
					(thickness 0.15)
				)
				(justify left bottom)
				(hide yes)
			)
		)
		(property "Description" ""
			(at 173.99 201.93 0)
			(effects
				(font
					(size 1.27 1.27)
				)
				(hide yes)
			)
		)
		(property "Manufacturer" "Murata"
			(at 194.31 222.25 0)
			(effects
				(font
					(size 1.27 1.27)
					(thickness 0.15)
				)
				(justify left bottom)
				(hide yes)
			)
		)
		(property "MPN" "GRM155R61H104KE14D"
			(at 191.77 222.25 0)
			(effects
				(font
					(size 1.27 1.27)
					(thickness 0.15)
				)
				(justify left bottom)
				(hide yes)
			)
		)
		(property "Val" "100n"
			(at 176.53 205.7463 90)
			(effects
				(font
					(size 1.27 1.27)
					(thickness 0.15)
				)
				(justify right)
			)
		)
		(property "License" "Apache-2.0"
			(at 196.85 222.25 0)
			(effects
				(font
					(size 1.27 1.27)
					(thickness 0.15)
				)
				(justify left bottom)
				(hide yes)
			)
		)
		(property "Author" "Antmicro"
			(at 199.39 222.25 0)
			(effects
				(font
					(size 1.27 1.27)
					(thickness 0.15)
				)
				(justify left bottom)
				(hide yes)
			)
		)
		(property "Voltage" "50V"
			(at 201.93 222.25 0)
			(effects
				(font
					(size 1.27 1.27)
				)
				(justify left bottom)
				(hide yes)
			)
		)
		(property "Dielectric" "X5R"
			(at 204.47 222.25 0)
			(effects
				(font
					(size 1.27 1.27)
				)
				(justify left bottom)
				(hide yes)
			)
		)
		(pin "1"
		)
		(pin "2"
		)
		(instances
			(project "jetson-orin-baseboard"
				(path ""
					(reference "C45")
					(unit 1)
				)
			)
		)
	)
	(symbol
		(lib_name "R_10k_0402_2")
		(lib_id "antmicroResistors0402:R_10k_0402")
		(at 30.48 76.2 0)
		(unit 1)
		(exclude_from_sim no)
		(in_bom yes)
		(on_board yes)
		(dnp no)
		(property "Reference" "R44"
			(at 35.56 75.565 0)
			(effects
				(font
					(size 1.27 1.27)
				)
				(justify left bottom)
			)
		)
		(property "Value" "R_10k_0402"
			(at 50.8 88.9 0)
			(effects
				(font
					(size 1.27 1.27)
					(thickness 0.15)
				)
				(justify left bottom)
				(hide yes)
			)
		)
		(property "Footprint" "antmicro-footprints:R_0402_1005Metric"
			(at 50.8 91.44 0)
			(effects
				(font
					(size 1.27 1.27)
					(thickness 0.15)
				)
				(justify left bottom)
				(hide yes)
			)
		)
		(property "Datasheet" "https://www.bourns.com/docs/product-datasheets/cr.pdf"
			(at 50.8 93.98 0)
			(effects
				(font
					(size 1.27 1.27)
					(thickness 0.15)
				)
				(justify left bottom)
				(hide yes)
			)
		)
		(property "Description" ""
			(at 30.48 76.2 0)
			(effects
				(font
					(size 1.27 1.27)
				)
				(hide yes)
			)
		)
		(property "Manufacturer" "Bourns"
			(at 50.8 99.06 0)
			(effects
				(font
					(size 1.27 1.27)
					(thickness 0.15)
				)
				(justify left bottom)
				(hide yes)
			)
		)
		(property "MPN" "CR0402-FX-1002GLF"
			(at 50.8 96.52 0)
			(effects
				(font
					(size 1.27 1.27)
					(thickness 0.15)
				)
				(justify left bottom)
				(hide yes)
			)
		)
		(property "Val" "10k"
			(at 27.305 75.565 0)
			(effects
				(font
					(size 1.27 1.27)
					(thickness 0.15)
				)
				(justify left bottom)
			)
		)
		(property "License" "Apache-2.0"
			(at 50.8 101.6 0)
			(effects
				(font
					(size 1.27 1.27)
					(thickness 0.15)
				)
				(justify left bottom)
				(hide yes)
			)
		)
		(property "Author" "Antmicro"
			(at 50.8 104.14 0)
			(effects
				(font
					(size 1.27 1.27)
					(thickness 0.15)
				)
				(justify left bottom)
				(hide yes)
			)
		)
		(property "Tolerance" "1%"
			(at 50.8 86.36 0)
			(effects
				(font
					(size 1.27 1.27)
				)
				(justify left bottom)
				(hide yes)
			)
		)
		(pin "1"
		)
		(pin "2"
		)
		(instances
			(project "jetson-orin-baseboard"
				(path ""
					(reference "R44")
					(unit 1)
				)
			)
		)
	)
	(symbol
		(lib_name "R_10k_0402_1")
		(lib_id "antmicroResistors0402:R_10k_0402")
		(at 29.21 217.17 0)
		(unit 1)
		(exclude_from_sim no)
		(in_bom yes)
		(on_board yes)
		(dnp no)
		(property "Reference" "R46"
			(at 34.29 216.535 0)
			(effects
				(font
					(size 1.27 1.27)
				)
				(justify left bottom)
			)
		)
		(property "Value" "R_10k_0402"
			(at 49.53 229.87 0)
			(effects
				(font
					(size 1.27 1.27)
					(thickness 0.15)
				)
				(justify left bottom)
				(hide yes)
			)
		)
		(property "Footprint" "antmicro-footprints:R_0402_1005Metric"
			(at 49.53 232.41 0)
			(effects
				(font
					(size 1.27 1.27)
					(thickness 0.15)
				)
				(justify left bottom)
				(hide yes)
			)
		)
		(property "Datasheet" "https://www.bourns.com/docs/product-datasheets/cr.pdf"
			(at 49.53 234.95 0)
			(effects
				(font
					(size 1.27 1.27)
					(thickness 0.15)
				)
				(justify left bottom)
				(hide yes)
			)
		)
		(property "Description" ""
			(at 29.21 217.17 0)
			(effects
				(font
					(size 1.27 1.27)
				)
				(hide yes)
			)
		)
		(property "Manufacturer" "Bourns"
			(at 49.53 240.03 0)
			(effects
				(font
					(size 1.27 1.27)
					(thickness 0.15)
				)
				(justify left bottom)
				(hide yes)
			)
		)
		(property "MPN" "CR0402-FX-1002GLF"
			(at 49.53 237.49 0)
			(effects
				(font
					(size 1.27 1.27)
					(thickness 0.15)
				)
				(justify left bottom)
				(hide yes)
			)
		)
		(property "Val" "10k"
			(at 25.4 216.535 0)
			(effects
				(font
					(size 1.27 1.27)
					(thickness 0.15)
				)
				(justify left bottom)
			)
		)
		(property "License" "Apache-2.0"
			(at 49.53 242.57 0)
			(effects
				(font
					(size 1.27 1.27)
					(thickness 0.15)
				)
				(justify left bottom)
				(hide yes)
			)
		)
		(property "Author" "Antmicro"
			(at 49.53 245.11 0)
			(effects
				(font
					(size 1.27 1.27)
					(thickness 0.15)
				)
				(justify left bottom)
				(hide yes)
			)
		)
		(property "Tolerance" "1%"
			(at 49.53 227.33 0)
			(effects
				(font
					(size 1.27 1.27)
				)
				(justify left bottom)
				(hide yes)
			)
		)
		(pin "1"
		)
		(pin "2"
		)
		(instances
			(project "jetson-orin-baseboard"
				(path ""
					(reference "R46")
					(unit 1)
				)
			)
		)
	)
	(symbol
		(lib_name "R_200R_0402_2")
		(lib_id "antmicroResistors0402:R_200R_0402")
		(at 118.11 80.01 0)
		(unit 1)
		(exclude_from_sim no)
		(in_bom yes)
		(on_board yes)
		(dnp no)
		(property "Reference" "R68"
			(at 123.19 79.375 0)
			(effects
				(font
					(size 1.27 1.27)
				)
				(justify left bottom)
			)
		)
		(property "Value" "R_200R_0402"
			(at 138.43 92.71 0)
			(effects
				(font
					(size 1.27 1.27)
					(thickness 0.15)
				)
				(justify left bottom)
				(hide yes)
			)
		)
		(property "Footprint" "antmicro-footprints:R_0402_1005Metric"
			(at 138.43 95.25 0)
			(effects
				(font
					(size 1.27 1.27)
					(thickness 0.15)
				)
				(justify left bottom)
				(hide yes)
			)
		)
		(property "Datasheet" "https://www.bourns.com/docs/product-datasheets/cr.pdf"
			(at 138.43 97.79 0)
			(effects
				(font
					(size 1.27 1.27)
					(thickness 0.15)
				)
				(justify left bottom)
				(hide yes)
			)
		)
		(property "Description" ""
			(at 118.11 80.01 0)
			(effects
				(font
					(size 1.27 1.27)
				)
				(hide yes)
			)
		)
		(property "Manufacturer" "Bourns"
			(at 138.43 102.87 0)
			(effects
				(font
					(size 1.27 1.27)
					(thickness 0.15)
				)
				(justify left bottom)
				(hide yes)
			)
		)
		(property "MPN" "CR0402-FX-2000GLF"
			(at 138.43 100.33 0)
			(effects
				(font
					(size 1.27 1.27)
					(thickness 0.15)
				)
				(justify left bottom)
				(hide yes)
			)
		)
		(property "Val" "200R"
			(at 113.03 79.375 0)
			(effects
				(font
					(size 1.27 1.27)
					(thickness 0.15)
				)
				(justify left bottom)
			)
		)
		(property "License" "Apache-2.0"
			(at 138.43 105.41 0)
			(effects
				(font
					(size 1.27 1.27)
					(thickness 0.15)
				)
				(justify left bottom)
				(hide yes)
			)
		)
		(property "Author" "Antmicro"
			(at 138.43 107.95 0)
			(effects
				(font
					(size 1.27 1.27)
					(thickness 0.15)
				)
				(justify left bottom)
				(hide yes)
			)
		)
		(property "Tolerance" "1%"
			(at 138.43 90.17 0)
			(effects
				(font
					(size 1.27 1.27)
				)
				(justify left bottom)
				(hide yes)
			)
		)
		(pin "1"
		)
		(pin "2"
		)
		(instances
			(project "jetson-orin-baseboard"
				(path ""
					(reference "R68")
					(unit 1)
				)
			)
		)
	)
	(symbol
		(lib_id "antmicropower:+3V3")
		(at 157.48 64.77 0)
		(unit 1)
		(exclude_from_sim no)
		(in_bom yes)
		(on_board yes)
		(dnp no)
		(property "Reference" "#PWR069"
			(at 157.48 68.58 0)
			(effects
				(font
					(size 1.27 1.27)
				)
				(justify left bottom)
				(hide yes)
			)
		)
		(property "Value" "+3V3"
			(at 154.305 60.96 0)
			(effects
				(font
					(size 1.27 1.27)
					(thickness 0.15)
				)
				(justify left)
			)
		)
		(property "Footprint" ""
			(at 172.72 72.39 0)
			(effects
				(font
					(size 1.27 1.27)
					(thickness 0.15)
				)
				(justify left bottom)
				(hide yes)
			)
		)
		(property "Datasheet" ""
			(at 172.72 74.93 0)
			(effects
				(font
					(size 1.27 1.27)
					(thickness 0.15)
				)
				(justify left bottom)
				(hide yes)
			)
		)
		(property "Description" ""
			(at 157.48 64.77 0)
			(effects
				(font
					(size 1.27 1.27)
				)
				(hide yes)
			)
		)
		(property "Author" "Antmicro"
			(at 172.72 67.31 0)
			(effects
				(font
					(size 1.27 1.27)
					(thickness 0.15)
				)
				(justify left bottom)
				(hide yes)
			)
		)
		(property "License" "Apache-2.0"
			(at 172.72 69.85 0)
			(effects
				(font
					(size 1.27 1.27)
					(thickness 0.15)
				)
				(justify left bottom)
				(hide yes)
			)
		)
		(pin "1"
		)
		(instances
			(project "jetson-orin-baseboard"
				(path ""
					(reference "#PWR069")
					(unit 1)
				)
			)
		)
	)
	(symbol
		(lib_id "antmicroResistors0402:R_200R_0402")
		(at 111.76 193.04 270)
		(mirror x)
		(unit 1)
		(exclude_from_sim no)
		(in_bom yes)
		(on_board yes)
		(dnp no)
		(property "Reference" "R73"
			(at 110.49 189.23 90)
			(effects
				(font
					(size 1.27 1.27)
				)
				(justify right)
			)
		)
		(property "Value" "R_200R_0402"
			(at 99.06 172.72 0)
			(effects
				(font
					(size 1.27 1.27)
					(thickness 0.15)
				)
				(justify left bottom)
				(hide yes)
			)
		)
		(property "Footprint" "antmicro-footprints:R_0402_1005Metric"
			(at 96.52 172.72 0)
			(effects
				(font
					(size 1.27 1.27)
					(thickness 0.15)
				)
				(justify left bottom)
				(hide yes)
			)
		)
		(property "Datasheet" "https://www.bourns.com/docs/product-datasheets/cr.pdf"
			(at 93.98 172.72 0)
			(effects
				(font
					(size 1.27 1.27)
					(thickness 0.15)
				)
				(justify left bottom)
				(hide yes)
			)
		)
		(property "Description" ""
			(at 111.76 193.04 0)
			(effects
				(font
					(size 1.27 1.27)
				)
				(hide yes)
			)
		)
		(property "Manufacturer" "Bourns"
			(at 88.9 172.72 0)
			(effects
				(font
					(size 1.27 1.27)
					(thickness 0.15)
				)
				(justify left bottom)
				(hide yes)
			)
		)
		(property "MPN" "CR0402-FX-2000GLF"
			(at 91.44 172.72 0)
			(effects
				(font
					(size 1.27 1.27)
					(thickness 0.15)
				)
				(justify left bottom)
				(hide yes)
			)
		)
		(property "Val" "200R"
			(at 110.49 191.77 90)
			(effects
				(font
					(size 1.27 1.27)
					(thickness 0.15)
				)
				(justify right)
			)
		)
		(property "License" "Apache-2.0"
			(at 86.36 172.72 0)
			(effects
				(font
					(size 1.27 1.27)
					(thickness 0.15)
				)
				(justify left bottom)
				(hide yes)
			)
		)
		(property "Author" "Antmicro"
			(at 83.82 172.72 0)
			(effects
				(font
					(size 1.27 1.27)
					(thickness 0.15)
				)
				(justify left bottom)
				(hide yes)
			)
		)
		(property "Tolerance" "1%"
			(at 101.6 172.72 0)
			(effects
				(font
					(size 1.27 1.27)
				)
				(justify left bottom)
				(hide yes)
			)
		)
		(pin "1"
		)
		(pin "2"
		)
		(instances
			(project "jetson-orin-baseboard"
				(path ""
					(reference "R73")
					(unit 1)
				)
			)
		)
	)
	(symbol
		(lib_id "antmicroResistors0402:R_0R_0402")
		(at 201.93 95.25 90)
		(unit 1)
		(exclude_from_sim no)
		(in_bom no)
		(on_board yes)
		(dnp yes)
		(property "Reference" "R79"
			(at 200.025 91.44 90)
			(effects
				(font
					(size 1.27 1.27)
				)
				(justify left)
			)
		)
		(property "Value" "R_0R_0402"
			(at 214.63 74.93 0)
			(effects
				(font
					(size 1.27 1.27)
					(thickness 0.15)
				)
				(justify left bottom)
				(hide yes)
			)
		)
		(property "Footprint" "antmicro-footprints:R_0402_1005Metric"
			(at 217.17 74.93 0)
			(effects
				(font
					(size 1.27 1.27)
					(thickness 0.15)
				)
				(justify left bottom)
				(hide yes)
			)
		)
		(property "Datasheet" "https://industrial.panasonic.com/cdbs/www-data/pdf/RDA0000/AOA0000C301.pdf"
			(at 219.71 74.93 0)
			(effects
				(font
					(size 1.27 1.27)
					(thickness 0.15)
				)
				(justify left bottom)
				(hide yes)
			)
		)
		(property "Description" ""
			(at 201.93 95.25 0)
			(effects
				(font
					(size 1.27 1.27)
				)
				(hide yes)
			)
		)
		(property "Manufacturer" "Panasonic"
			(at 224.79 74.93 0)
			(effects
				(font
					(size 1.27 1.27)
					(thickness 0.15)
				)
				(justify left bottom)
				(hide yes)
			)
		)
		(property "MPN" "ERJ2GE0R00X"
			(at 222.25 74.93 0)
			(effects
				(font
					(size 1.27 1.27)
					(thickness 0.15)
				)
				(justify left bottom)
				(hide yes)
			)
		)
		(property "Val" "0R"
			(at 200.025 93.98 90)
			(effects
				(font
					(size 1.27 1.27)
					(thickness 0.15)
				)
				(justify left)
			)
		)
		(property "License" "Apache-2.0"
			(at 227.33 74.93 0)
			(effects
				(font
					(size 1.27 1.27)
					(thickness 0.15)
				)
				(justify left bottom)
				(hide yes)
			)
		)
		(property "Author" "Antmicro"
			(at 229.87 74.93 0)
			(effects
				(font
					(size 1.27 1.27)
					(thickness 0.15)
				)
				(justify left bottom)
				(hide yes)
			)
		)
		(property "Tolerance" "~"
			(at 212.09 74.93 0)
			(effects
				(font
					(size 1.27 1.27)
				)
				(justify left bottom)
				(hide yes)
			)
		)
		(property "Current" "1A"
			(at 232.41 74.93 0)
			(effects
				(font
					(size 1.27 1.27)
					(thickness 0.15)
				)
				(justify left bottom)
				(hide yes)
			)
		)
		(pin "1"
		)
		(pin "2"
		)
		(instances
			(project "jetson-orin-baseboard"
				(path ""
					(reference "R79")
					(unit 1)
				)
			)
		)
	)
	(symbol
		(lib_name "GND_3")
		(lib_id "antmicropower:GND")
		(at 27.94 46.99 0)
		(mirror y)
		(unit 1)
		(exclude_from_sim no)
		(in_bom yes)
		(on_board yes)
		(dnp no)
		(property "Reference" "#PWR054"
			(at 27.94 53.34 0)
			(effects
				(font
					(size 1.27 1.27)
				)
				(justify left bottom)
				(hide yes)
			)
		)
		(property "Value" "GND"
			(at 27.94 50.8 0)
			(effects
				(font
					(size 1.27 1.27)
					(thickness 0.15)
				)
			)
		)
		(property "Footprint" ""
			(at 19.05 54.61 0)
			(effects
				(font
					(size 1.27 1.27)
					(thickness 0.15)
				)
				(justify left bottom)
				(hide yes)
			)
		)
		(property "Datasheet" ""
			(at 19.05 59.69 0)
			(effects
				(font
					(size 1.27 1.27)
					(thickness 0.15)
				)
				(justify left bottom)
				(hide yes)
			)
		)
		(property "Description" ""
			(at 27.94 46.99 0)
			(effects
				(font
					(size 1.27 1.27)
				)
				(hide yes)
			)
		)
		(property "Author" "Antmicro"
			(at 19.05 54.61 0)
			(effects
				(font
					(size 1.27 1.27)
					(thickness 0.15)
				)
				(justify left bottom)
				(hide yes)
			)
		)
		(property "License" "Apache-2.0"
			(at 19.05 57.15 0)
			(effects
				(font
					(size 1.27 1.27)
					(thickness 0.15)
				)
				(justify left bottom)
				(hide yes)
			)
		)
		(pin "1"
		)
		(instances
			(project "jetson-orin-baseboard"
				(path ""
					(reference "#PWR054")
					(unit 1)
				)
			)
		)
	)
	(symbol
		(lib_name "TP_0.75mm_SMD_7")
		(lib_id "antmicroTestPoints:TP_0.75mm_SMD")
		(at 105.41 106.68 0)
		(unit 1)
		(exclude_from_sim no)
		(in_bom no)
		(on_board yes)
		(dnp no)
		(property "Reference" "TP19"
			(at 109.22 107.315 0)
			(effects
				(font
					(size 1.27 1.27)
				)
				(justify left bottom)
			)
		)
		(property "Value" "TP_0.75mm_SMD"
			(at 115.57 110.49 0)
			(effects
				(font
					(size 1.27 1.27)
					(thickness 0.15)
				)
				(justify left bottom)
				(hide yes)
			)
		)
		(property "Footprint" "antmicro-footprints:TP_SMD_0.75mm"
			(at 115.57 113.03 0)
			(effects
				(font
					(size 1.27 1.27)
					(thickness 0.15)
				)
				(justify left bottom)
				(hide yes)
			)
		)
		(property "Datasheet" ""
			(at 123.19 119.38 0)
			(effects
				(font
					(size 1.27 1.27)
					(thickness 0.15)
				)
				(justify left bottom)
				(hide yes)
			)
		)
		(property "Description" ""
			(at 105.41 106.68 0)
			(effects
				(font
					(size 1.27 1.27)
				)
				(hide yes)
			)
		)
		(property "MPN" ""
			(at 116.205 118.11 0)
			(effects
				(font
					(size 1.27 1.27)
					(thickness 0.15)
				)
				(justify left bottom)
				(hide yes)
			)
		)
		(property "Manufacturer" ""
			(at 116.205 113.03 0)
			(effects
				(font
					(size 1.27 1.27)
					(thickness 0.15)
				)
				(justify left bottom)
				(hide yes)
			)
		)
		(property "Author" "Antmicro"
			(at 115.57 115.57 0)
			(effects
				(font
					(size 1.27 1.27)
					(thickness 0.15)
				)
				(justify left bottom)
				(hide yes)
			)
		)
		(property "License" "Apache-2.0"
			(at 115.57 118.11 0)
			(effects
				(font
					(size 1.27 1.27)
					(thickness 0.15)
				)
				(justify left bottom)
				(hide yes)
			)
		)
		(pin "1"
		)
		(instances
			(project "jetson-orin-baseboard"
				(path ""
					(reference "TP19")
					(unit 1)
				)
			)
		)
	)
	(symbol
		(lib_id "antmicroCapacitors0402:C_10u_0402")
		(at 193.04 266.7 90)
		(unit 1)
		(exclude_from_sim no)
		(in_bom yes)
		(on_board yes)
		(dnp no)
		(fields_autoplaced yes)
		(property "Reference" "C35"
			(at 190.5 262.8836 90)
			(effects
				(font
					(size 1.27 1.27)
					(thickness 0.15)
				)
				(justify left)
			)
		)
		(property "Value" "C_10u_0402"
			(at 203.2 246.38 0)
			(effects
				(font
					(size 1.27 1.27)
					(thickness 0.15)
				)
				(justify left bottom)
				(hide yes)
			)
		)
		(property "Footprint" "antmicro-footprints:C_0402_1005Metric"
			(at 205.74 246.38 0)
			(effects
				(font
					(size 1.27 1.27)
					(thickness 0.15)
				)
				(justify left bottom)
				(hide yes)
			)
		)
		(property "Datasheet" "https://www.yageo.com/en/Chart/Download/pdf/CC0402MRX5R5BB106"
			(at 208.28 246.38 0)
			(effects
				(font
					(size 1.27 1.27)
					(thickness 0.15)
				)
				(justify left bottom)
				(hide yes)
			)
		)
		(property "Description" ""
			(at 193.04 266.7 0)
			(effects
				(font
					(size 1.27 1.27)
				)
				(hide yes)
			)
		)
		(property "MPN" "CC0402MRX5R5BB106"
			(at 210.82 246.38 0)
			(effects
				(font
					(size 1.27 1.27)
					(thickness 0.15)
				)
				(justify left bottom)
				(hide yes)
			)
		)
		(property "Manufacturer" "YAGEO"
			(at 213.36 246.38 0)
			(effects
				(font
					(size 1.27 1.27)
					(thickness 0.15)
				)
				(justify left bottom)
				(hide yes)
			)
		)
		(property "License" "Apache-2.0"
			(at 215.9 246.38 0)
			(effects
				(font
					(size 1.27 1.27)
					(thickness 0.15)
				)
				(justify left bottom)
				(hide yes)
			)
		)
		(property "Author" "Antmicro"
			(at 218.44 246.38 0)
			(effects
				(font
					(size 1.27 1.27)
					(thickness 0.15)
				)
				(justify left bottom)
				(hide yes)
			)
		)
		(property "Val" "10u"
			(at 190.5 265.4236 90)
			(effects
				(font
					(size 1.27 1.27)
					(thickness 0.15)
				)
				(justify left)
			)
		)
		(property "Voltage" ""
			(at 220.98 246.38 0)
			(effects
				(font
					(size 1.27 1.27)
				)
				(justify left bottom)
				(hide yes)
			)
		)
		(property "Dielectric" ""
			(at 223.52 246.38 0)
			(effects
				(font
					(size 1.27 1.27)
				)
				(justify left bottom)
				(hide yes)
			)
		)
		(pin "1"
		)
		(pin "2"
		)
		(instances
			(project "jetson-orin-baseboard"
				(path ""
					(reference "C35")
					(unit 1)
				)
			)
		)
	)
	(symbol
		(lib_name "GND_3")
		(lib_id "antmicropower:GND")
		(at 179.07 73.66 0)
		(mirror y)
		(unit 1)
		(exclude_from_sim no)
		(in_bom yes)
		(on_board yes)
		(dnp no)
		(property "Reference" "#PWR075"
			(at 179.07 80.01 0)
			(effects
				(font
					(size 1.27 1.27)
				)
				(justify left bottom)
				(hide yes)
			)
		)
		(property "Value" "GND"
			(at 179.07 77.47 0)
			(effects
				(font
					(size 1.27 1.27)
					(thickness 0.15)
				)
			)
		)
		(property "Footprint" ""
			(at 170.18 81.28 0)
			(effects
				(font
					(size 1.27 1.27)
					(thickness 0.15)
				)
				(justify left bottom)
				(hide yes)
			)
		)
		(property "Datasheet" ""
			(at 170.18 86.36 0)
			(effects
				(font
					(size 1.27 1.27)
					(thickness 0.15)
				)
				(justify left bottom)
				(hide yes)
			)
		)
		(property "Description" ""
			(at 179.07 73.66 0)
			(effects
				(font
					(size 1.27 1.27)
				)
				(hide yes)
			)
		)
		(property "Author" "Antmicro"
			(at 170.18 81.28 0)
			(effects
				(font
					(size 1.27 1.27)
					(thickness 0.15)
				)
				(justify left bottom)
				(hide yes)
			)
		)
		(property "License" "Apache-2.0"
			(at 170.18 83.82 0)
			(effects
				(font
					(size 1.27 1.27)
					(thickness 0.15)
				)
				(justify left bottom)
				(hide yes)
			)
		)
		(pin "1"
		)
		(instances
			(project "jetson-orin-baseboard"
				(path ""
					(reference "#PWR075")
					(unit 1)
				)
			)
		)
	)
	(symbol
		(lib_name "TP_0.75mm_SMD_10")
		(lib_id "antmicroTestPoints:TP_0.75mm_SMD")
		(at 195.58 209.55 180)
		(unit 1)
		(exclude_from_sim no)
		(in_bom no)
		(on_board yes)
		(dnp no)
		(property "Reference" "TP27"
			(at 191.77 209.55 0)
			(effects
				(font
					(size 1.27 1.27)
				)
				(justify left)
			)
		)
		(property "Value" "TP_0.75mm_SMD"
			(at 185.42 205.74 0)
			(effects
				(font
					(size 1.27 1.27)
					(thickness 0.15)
				)
				(justify left bottom)
				(hide yes)
			)
		)
		(property "Footprint" "antmicro-footprints:TP_SMD_0.75mm"
			(at 185.42 203.2 0)
			(effects
				(font
					(size 1.27 1.27)
					(thickness 0.15)
				)
				(justify left bottom)
				(hide yes)
			)
		)
		(property "Datasheet" ""
			(at 177.8 196.85 0)
			(effects
				(font
					(size 1.27 1.27)
					(thickness 0.15)
				)
				(justify left bottom)
				(hide yes)
			)
		)
		(property "Description" ""
			(at 195.58 209.55 0)
			(effects
				(font
					(size 1.27 1.27)
				)
				(hide yes)
			)
		)
		(property "MPN" ""
			(at 184.785 198.12 0)
			(effects
				(font
					(size 1.27 1.27)
					(thickness 0.15)
				)
				(justify left bottom)
				(hide yes)
			)
		)
		(property "Manufacturer" ""
			(at 184.785 203.2 0)
			(effects
				(font
					(size 1.27 1.27)
					(thickness 0.15)
				)
				(justify left bottom)
				(hide yes)
			)
		)
		(property "Author" "Antmicro"
			(at 185.42 200.66 0)
			(effects
				(font
					(size 1.27 1.27)
					(thickness 0.15)
				)
				(justify left bottom)
				(hide yes)
			)
		)
		(property "License" "Apache-2.0"
			(at 185.42 198.12 0)
			(effects
				(font
					(size 1.27 1.27)
					(thickness 0.15)
				)
				(justify left bottom)
				(hide yes)
			)
		)
		(pin "1"
		)
		(instances
			(project "jetson-orin-baseboard"
				(path ""
					(reference "TP27")
					(unit 1)
				)
			)
		)
	)
	(symbol
		(lib_name "+3V3_3")
		(lib_id "antmicropower:+3V3")
		(at 140.97 119.38 0)
		(unit 1)
		(exclude_from_sim no)
		(in_bom yes)
		(on_board yes)
		(dnp no)
		(property "Reference" "#PWR0276"
			(at 140.97 123.19 0)
			(effects
				(font
					(size 1.27 1.27)
				)
				(justify left bottom)
				(hide yes)
			)
		)
		(property "Value" "+3V3"
			(at 137.795 116.205 0)
			(effects
				(font
					(size 1.27 1.27)
					(thickness 0.15)
				)
				(justify left bottom)
			)
		)
		(property "Footprint" ""
			(at 156.21 127 0)
			(effects
				(font
					(size 1.27 1.27)
					(thickness 0.15)
				)
				(justify left bottom)
				(hide yes)
			)
		)
		(property "Datasheet" ""
			(at 156.21 129.54 0)
			(effects
				(font
					(size 1.27 1.27)
					(thickness 0.15)
				)
				(justify left bottom)
				(hide yes)
			)
		)
		(property "Description" ""
			(at 140.97 119.38 0)
			(effects
				(font
					(size 1.27 1.27)
				)
				(hide yes)
			)
		)
		(property "Author" "Antmicro"
			(at 156.21 121.92 0)
			(effects
				(font
					(size 1.27 1.27)
					(thickness 0.15)
				)
				(justify left bottom)
				(hide yes)
			)
		)
		(property "License" "Apache-2.0"
			(at 156.21 124.46 0)
			(effects
				(font
					(size 1.27 1.27)
					(thickness 0.15)
				)
				(justify left bottom)
				(hide yes)
			)
		)
		(pin "1"
		)
		(instances
			(project "jetson-orin-baseboard"
				(path ""
					(reference "#PWR0276")
					(unit 1)
				)
			)
		)
	)
	(symbol
		(lib_name "LED_G_0603_LTST-C190GKT_2")
		(lib_id "antmicroLEDIndicationDiscrete:LED_G_0603_LTST-C190GKT")
		(at 134.62 80.01 0)
		(mirror y)
		(unit 1)
		(exclude_from_sim no)
		(in_bom yes)
		(on_board yes)
		(dnp no)
		(property "Reference" "D4"
			(at 134.62 79.375 0)
			(effects
				(font
					(size 1.27 1.27)
				)
				(justify right bottom)
			)
		)
		(property "Value" "LED_G_0603_LTST-C190GKT"
			(at 111.76 87.63 0)
			(effects
				(font
					(size 1.27 1.27)
					(thickness 0.15)
				)
				(justify left bottom)
				(hide yes)
			)
		)
		(property "Footprint" "antmicro-footprints:LED_0603_1608Metric_G"
			(at 111.76 90.17 0)
			(effects
				(font
					(size 1.27 1.27)
					(thickness 0.15)
				)
				(justify left bottom)
				(hide yes)
			)
		)
		(property "Datasheet" "https://media.digikey.com/pdf/Data%20Sheets/Lite-On%20PDFs/LTST-C190GKT.pdf"
			(at 111.76 92.71 0)
			(effects
				(font
					(size 1.27 1.27)
					(thickness 0.15)
				)
				(justify left bottom)
				(hide yes)
			)
		)
		(property "Description" ""
			(at 134.62 80.01 0)
			(effects
				(font
					(size 1.27 1.27)
				)
				(hide yes)
			)
		)
		(property "MPN" "LTST-C190GKT"
			(at 111.76 95.25 0)
			(effects
				(font
					(size 1.27 1.27)
					(thickness 0.15)
				)
				(justify left bottom)
				(hide yes)
			)
		)
		(property "Manufacturer" "Lite-On"
			(at 111.76 97.79 0)
			(effects
				(font
					(size 1.27 1.27)
					(thickness 0.15)
				)
				(justify left bottom)
				(hide yes)
			)
		)
		(property "Author" "Antmicro"
			(at 111.76 100.33 0)
			(effects
				(font
					(size 1.27 1.27)
					(thickness 0.15)
				)
				(justify left bottom)
				(hide yes)
			)
		)
		(property "License" "Apache-2.0"
			(at 111.76 102.87 0)
			(effects
				(font
					(size 1.27 1.27)
					(thickness 0.15)
				)
				(justify left bottom)
				(hide yes)
			)
		)
		(property "Color" "Green"
			(at 128.905 76.835 0)
			(effects
				(font
					(size 1.27 1.27)
				)
				(justify right bottom)
			)
		)
		(pin "1"
		)
		(pin "2"
		)
		(instances
			(project "jetson-orin-baseboard"
				(path ""
					(reference "D4")
					(unit 1)
				)
			)
		)
	)
	(symbol
		(lib_name "GND_3")
		(lib_id "antmicropower:GND")
		(at 168.91 73.66 0)
		(mirror y)
		(unit 1)
		(exclude_from_sim no)
		(in_bom yes)
		(on_board yes)
		(dnp no)
		(fields_autoplaced yes)
		(property "Reference" "#PWR071"
			(at 168.91 80.01 0)
			(effects
				(font
					(size 1.27 1.27)
				)
				(justify left bottom)
				(hide yes)
			)
		)
		(property "Value" "GND"
			(at 168.91 77.47 0)
			(effects
				(font
					(size 1.27 1.27)
					(thickness 0.15)
				)
			)
		)
		(property "Footprint" ""
			(at 160.02 81.28 0)
			(effects
				(font
					(size 1.27 1.27)
					(thickness 0.15)
				)
				(justify left bottom)
				(hide yes)
			)
		)
		(property "Datasheet" ""
			(at 160.02 86.36 0)
			(effects
				(font
					(size 1.27 1.27)
					(thickness 0.15)
				)
				(justify left bottom)
				(hide yes)
			)
		)
		(property "Description" ""
			(at 168.91 73.66 0)
			(effects
				(font
					(size 1.27 1.27)
				)
				(hide yes)
			)
		)
		(property "Author" "Antmicro"
			(at 160.02 81.28 0)
			(effects
				(font
					(size 1.27 1.27)
					(thickness 0.15)
				)
				(justify left bottom)
				(hide yes)
			)
		)
		(property "License" "Apache-2.0"
			(at 160.02 83.82 0)
			(effects
				(font
					(size 1.27 1.27)
					(thickness 0.15)
				)
				(justify left bottom)
				(hide yes)
			)
		)
		(pin "1"
		)
		(instances
			(project "jetson-orin-baseboard"
				(path ""
					(reference "#PWR071")
					(unit 1)
				)
			)
		)
	)
)
